G04 ================== begin FILE IDENTIFICATION RECORD ==================*
G04 Layout Name:  12004-1.brd*
G04 Film Name:    L1*
G04 File Format:  Gerber RS274X*
G04 File Origin:  Cadence Allegro 16.2-S033*
G04 Origin Date:  Tue Oct 16 14:36:00 2012*
G04 *
G04 Layer:  VIA CLASS/TOP*
G04 Layer:  PIN/TOP*
G04 Layer:  ETCH/TOP*
G04 Layer:  DRAWING FORMAT/LAYER_PCB_STORY*
G04 Layer:  DRAWING FORMAT/LAYER_L1*
G04 *
G04 Offset:    (0.00 0.00)*
G04 Mirror:    No*
G04 Mode:      Positive*
G04 Rotation:  0*
G04 FullContactRelief:  No*
G04 UndefLineWidth:     6.00*
G04 ================== end FILE IDENTIFICATION RECORD ====================*
%FSLAX35Y35*MOIN*%
%IR0*IPPOS*OFA0.00000B0.00000*MIA0B0*SFA1.00000B1.00000*%
%AMMACRO47*
4,1,40,.017,-.013,
.017,.013,
.016939,.013695,
.016759,.014368,
.016464,.015,
.016064,.015571,
.015571,.016064,
.015,.016464,
.014368,.016759,
.013695,.016939,
.013,.017,
-.013,.017,
-.013695,.016939,
-.014368,.016759,
-.015,.016464,
-.015571,.016064,
-.016064,.015571,
-.016464,.015,
-.016759,.014368,
-.016939,.013695,
-.017,.013,
-.017,-.013,
-.016939,-.013695,
-.016759,-.014368,
-.016464,-.015,
-.016064,-.015571,
-.015571,-.016064,
-.015,-.016464,
-.014368,-.016759,
-.013695,-.016939,
-.013,-.017,
.013,-.017,
.013695,-.016939,
.014368,-.016759,
.015,-.016464,
.015571,-.016064,
.016064,-.015571,
.016464,-.015,
.016759,-.014368,
.016939,-.013695,
.017,-.013,
0.0*
%
%ADD47MACRO47*%
%AMMACRO42*
4,1,40,.013,.017,
-.013,.017,
-.013695,.016939,
-.014368,.016759,
-.015,.016464,
-.015571,.016064,
-.016064,.015571,
-.016464,.015,
-.016759,.014368,
-.016939,.013695,
-.017,.013,
-.017,-.013,
-.016939,-.013695,
-.016759,-.014368,
-.016464,-.015,
-.016064,-.015571,
-.015571,-.016064,
-.015,-.016464,
-.014368,-.016759,
-.013695,-.016939,
-.013,-.017,
.013,-.017,
.013695,-.016939,
.014368,-.016759,
.015,-.016464,
.015571,-.016064,
.016064,-.015571,
.016464,-.015,
.016759,-.014368,
.016939,-.013695,
.017,-.013,
.017,.013,
.016939,.013695,
.016759,.014368,
.016464,.015,
.016064,.015571,
.015571,.016064,
.015,.016464,
.014368,.016759,
.013695,.016939,
.013,.017,
0.0*
%
%ADD42MACRO42*%
%ADD83R,.045X.11*%
%ADD49R,.11X.055*%
%ADD10C,.01*%
%ADD14C,.02*%
%ADD12C,.022*%
%ADD92R,.126X.028*%
%ADD34C,.032*%
%ADD16C,.05*%
%ADD59R,.064X.136*%
%ADD82C,.061*%
%ADD91R,.165X.028*%
%ADD36C,.018*%
%ADD53R,.167X.09*%
%ADD35C,.055*%
%ADD15C,.046*%
%ADD13C,.028*%
%ADD11R,.05X.05*%
%AMMACRO25*
4,1,40,.011,-.007,
.011,.007,
.010939,.007695,
.010759,.008368,
.010464,.009,
.010064,.009571,
.009571,.010064,
.009,.010464,
.008368,.010759,
.007695,.010939,
.007,.011,
-.007,.011,
-.007695,.010939,
-.008368,.010759,
-.009,.010464,
-.009571,.010064,
-.010064,.009571,
-.010464,.009,
-.010759,.008368,
-.010939,.007695,
-.011,.007,
-.011,-.007,
-.010939,-.007695,
-.010759,-.008368,
-.010464,-.009,
-.010064,-.009571,
-.009571,-.010064,
-.009,-.010464,
-.008368,-.010759,
-.007695,-.010939,
-.007,-.011,
.007,-.011,
.007695,-.010939,
.008368,-.010759,
.009,-.010464,
.009571,-.010064,
.010064,-.009571,
.010464,-.009,
.010759,-.008368,
.010939,-.007695,
.011,-.007,
0.0*
%
%ADD25MACRO25*%
%AMMACRO23*
4,1,40,.007,.011,
-.007,.011,
-.007695,.010939,
-.008368,.010759,
-.009,.010464,
-.009571,.010064,
-.010064,.009571,
-.010464,.009,
-.010759,.008368,
-.010939,.007695,
-.011,.007,
-.011,-.007,
-.010939,-.007695,
-.010759,-.008368,
-.010464,-.009,
-.010064,-.009571,
-.009571,-.010064,
-.009,-.010464,
-.008368,-.010759,
-.007695,-.010939,
-.007,-.011,
.007,-.011,
.007695,-.010939,
.008368,-.010759,
.009,-.010464,
.009571,-.010064,
.010064,-.009571,
.010464,-.009,
.010759,-.008368,
.010939,-.007695,
.011,-.007,
.011,.007,
.010939,.007695,
.010759,.008368,
.010464,.009,
.010064,.009571,
.009571,.010064,
.009,.010464,
.008368,.010759,
.007695,.010939,
.007,.011,
0.0*
%
%ADD23MACRO23*%
%AMMACRO30*
4,1,40,-.012,.008,
-.012,-.008,
-.011939,-.008695,
-.011759,-.009368,
-.011464,-.01,
-.011064,-.010571,
-.010571,-.011064,
-.01,-.011464,
-.009368,-.011759,
-.008695,-.011939,
-.008,-.012,
.008,-.012,
.008695,-.011939,
.009368,-.011759,
.01,-.011464,
.010571,-.011064,
.011064,-.010571,
.011464,-.01,
.011759,-.009368,
.011939,-.008695,
.012,-.008,
.012,.008,
.011939,.008695,
.011759,.009368,
.011464,.01,
.011064,.010571,
.010571,.011064,
.01,.011464,
.009368,.011759,
.008695,.011939,
.008,.012,
-.008,.012,
-.008695,.011939,
-.009368,.011759,
-.01,.011464,
-.010571,.011064,
-.011064,.010571,
-.011464,.01,
-.011759,.009368,
-.011939,.008695,
-.012,.008,
0.0*
%
%ADD30MACRO30*%
%AMMACRO61*
4,1,40,.008,.012,
-.008,.012,
-.008695,.011939,
-.009368,.011759,
-.01,.011464,
-.010571,.011064,
-.011064,.010571,
-.011464,.01,
-.011759,.009368,
-.011939,.008695,
-.012,.008,
-.012,-.008,
-.011939,-.008695,
-.011759,-.009368,
-.011464,-.01,
-.011064,-.010571,
-.010571,-.011064,
-.01,-.011464,
-.009368,-.011759,
-.008695,-.011939,
-.008,-.012,
.008,-.012,
.008695,-.011939,
.009368,-.011759,
.01,-.011464,
.010571,-.011064,
.011064,-.010571,
.011464,-.01,
.011759,-.009368,
.011939,-.008695,
.012,-.008,
.012,.008,
.011939,.008695,
.011759,.009368,
.011464,.01,
.011064,.010571,
.010571,.011064,
.01,.011464,
.009368,.011759,
.008695,.011939,
.008,.012,
0.0*
%
%ADD61MACRO61*%
%AMMACRO44*
4,1,40,-.013,-.017,
.013,-.017,
.013695,-.016939,
.014368,-.016759,
.015,-.016464,
.015571,-.016064,
.016064,-.015571,
.016464,-.015,
.016759,-.014368,
.016939,-.013695,
.017,-.013,
.017,.013,
.016939,.013695,
.016759,.014368,
.016464,.015,
.016064,.015571,
.015571,.016064,
.015,.016464,
.014368,.016759,
.013695,.016939,
.013,.017,
-.013,.017,
-.013695,.016939,
-.014368,.016759,
-.015,.016464,
-.015571,.016064,
-.016064,.015571,
-.016464,.015,
-.016759,.014368,
-.016939,.013695,
-.017,.013,
-.017,-.013,
-.016939,-.013695,
-.016759,-.014368,
-.016464,-.015,
-.016064,-.015571,
-.015571,-.016064,
-.015,-.016464,
-.014368,-.016759,
-.013695,-.016939,
-.013,-.017,
0.0*
%
%ADD44MACRO44*%
%AMMACRO65*
4,1,6,-.025,-.0135,
-.005,.0065,
-.005,.0135,
.005,.0135,
.005,.0065,
.025,-.0135,
-.025,-.0135,
0.0*
%
%ADD65MACRO65*%
%AMMACRO57*
4,1,40,-.017,.013,
-.017,-.013,
-.016939,-.013695,
-.016759,-.014368,
-.016464,-.015,
-.016064,-.015571,
-.015571,-.016064,
-.015,-.016464,
-.014368,-.016759,
-.013695,-.016939,
-.013,-.017,
.013,-.017,
.013695,-.016939,
.014368,-.016759,
.015,-.016464,
.015571,-.016064,
.016064,-.015571,
.016464,-.015,
.016759,-.014368,
.016939,-.013695,
.017,-.013,
.017,.013,
.016939,.013695,
.016759,.014368,
.016464,.015,
.016064,.015571,
.015571,.016064,
.015,.016464,
.014368,.016759,
.013695,.016939,
.013,.017,
-.013,.017,
-.013695,.016939,
-.014368,.016759,
-.015,.016464,
-.015571,.016064,
-.016064,.015571,
-.016464,.015,
-.016759,.014368,
-.016939,.013695,
-.017,.013,
0.0*
%
%ADD57MACRO57*%
%AMMACRO77*
4,1,6,.005,.0135,
.005,.0065,
.025,-.0135,
-.025,-.0135,
-.005,.0065,
-.005,.0135,
.005,.0135,
0.0*
%
%ADD77MACRO77*%
%AMMACRO76*
4,1,20,.0655,-.1095,
.051,-.1095,
.051,-.12,
.0375,-.12,
.0375,-.1095,
-.0375,-.1095,
-.0375,-.12,
-.051,-.12,
-.051,-.1095,
-.0655,-.1095,
-.0655,.1095,
-.051,.1095,
-.051,.12,
-.0375,.12,
-.0375,.1095,
.0375,.1095,
.0375,.12,
.051,.12,
.051,.1095,
.0655,.1095,
.0655,-.1095,
0.0*
%
%ADD76MACRO76*%
%AMMACRO26*
4,1,40,.011,-.007,
.011,.007,
.010939,.007695,
.010759,.008368,
.010464,.009,
.010064,.009571,
.009571,.010064,
.009,.010464,
.008368,.010759,
.007695,.010939,
.007,.011,
-.007,.011,
-.007695,.010939,
-.008368,.010759,
-.009,.010464,
-.009571,.010064,
-.010064,.009571,
-.010464,.009,
-.010759,.008368,
-.010939,.007695,
-.011,.007,
-.011,-.007,
-.010939,-.007695,
-.010759,-.008368,
-.010464,-.009,
-.010064,-.009571,
-.009571,-.010064,
-.009,-.010464,
-.008368,-.010759,
-.007695,-.010939,
-.007,-.011,
.007,-.011,
.007695,-.010939,
.008368,-.010759,
.009,-.010464,
.009571,-.010064,
.010064,-.009571,
.010464,-.009,
.010759,-.008368,
.010939,-.007695,
.011,-.007,
0.0*
%
%ADD26MACRO26*%
%AMMACRO24*
4,1,40,.007,.011,
-.007,.011,
-.007695,.010939,
-.008368,.010759,
-.009,.010464,
-.009571,.010064,
-.010064,.009571,
-.010464,.009,
-.010759,.008368,
-.010939,.007695,
-.011,.007,
-.011,-.007,
-.010939,-.007695,
-.010759,-.008368,
-.010464,-.009,
-.010064,-.009571,
-.009571,-.010064,
-.009,-.010464,
-.008368,-.010759,
-.007695,-.010939,
-.007,-.011,
.007,-.011,
.007695,-.010939,
.008368,-.010759,
.009,-.010464,
.009571,-.010064,
.010064,-.009571,
.010464,-.009,
.010759,-.008368,
.010939,-.007695,
.011,-.007,
.011,.007,
.010939,.007695,
.010759,.008368,
.010464,.009,
.010064,.009571,
.009571,.010064,
.009,.010464,
.008368,.010759,
.007695,.010939,
.007,.011,
0.0*
%
%ADD24MACRO24*%
%AMMACRO29*
4,1,40,-.012,.008,
-.012,-.008,
-.011939,-.008695,
-.011759,-.009368,
-.011464,-.01,
-.011064,-.010571,
-.010571,-.011064,
-.01,-.011464,
-.009368,-.011759,
-.008695,-.011939,
-.008,-.012,
.008,-.012,
.008695,-.011939,
.009368,-.011759,
.01,-.011464,
.010571,-.011064,
.011064,-.010571,
.011464,-.01,
.011759,-.009368,
.011939,-.008695,
.012,-.008,
.012,.008,
.011939,.008695,
.011759,.009368,
.011464,.01,
.011064,.010571,
.010571,.011064,
.01,.011464,
.009368,.011759,
.008695,.011939,
.008,.012,
-.008,.012,
-.008695,.011939,
-.009368,.011759,
-.01,.011464,
-.010571,.011064,
-.011064,.010571,
-.011464,.01,
-.011759,.009368,
-.011939,.008695,
-.012,.008,
0.0*
%
%ADD29MACRO29*%
%AMMACRO60*
4,1,40,.008,.012,
-.008,.012,
-.008695,.011939,
-.009368,.011759,
-.01,.011464,
-.010571,.011064,
-.011064,.010571,
-.011464,.01,
-.011759,.009368,
-.011939,.008695,
-.012,.008,
-.012,-.008,
-.011939,-.008695,
-.011759,-.009368,
-.011464,-.01,
-.011064,-.010571,
-.010571,-.011064,
-.01,-.011464,
-.009368,-.011759,
-.008695,-.011939,
-.008,-.012,
.008,-.012,
.008695,-.011939,
.009368,-.011759,
.01,-.011464,
.010571,-.011064,
.011064,-.010571,
.011464,-.01,
.011759,-.009368,
.011939,-.008695,
.012,-.008,
.012,.008,
.011939,.008695,
.011759,.009368,
.011464,.01,
.011064,.010571,
.010571,.011064,
.01,.011464,
.009368,.011759,
.008695,.011939,
.008,.012,
0.0*
%
%ADD60MACRO60*%
%AMMACRO45*
4,1,40,-.013,-.017,
.013,-.017,
.013695,-.016939,
.014368,-.016759,
.015,-.016464,
.015571,-.016064,
.016064,-.015571,
.016464,-.015,
.016759,-.014368,
.016939,-.013695,
.017,-.013,
.017,.013,
.016939,.013695,
.016759,.014368,
.016464,.015,
.016064,.015571,
.015571,.016064,
.015,.016464,
.014368,.016759,
.013695,.016939,
.013,.017,
-.013,.017,
-.013695,.016939,
-.014368,.016759,
-.015,.016464,
-.015571,.016064,
-.016064,.015571,
-.016464,.015,
-.016759,.014368,
-.016939,.013695,
-.017,.013,
-.017,-.013,
-.016939,-.013695,
-.016759,-.014368,
-.016464,-.015,
-.016064,-.015571,
-.015571,-.016064,
-.015,-.016464,
-.014368,-.016759,
-.013695,-.016939,
-.013,-.017,
0.0*
%
%ADD45MACRO45*%
%AMMACRO58*
4,1,40,-.017,.013,
-.017,-.013,
-.016939,-.013695,
-.016759,-.014368,
-.016464,-.015,
-.016064,-.015571,
-.015571,-.016064,
-.015,-.016464,
-.014368,-.016759,
-.013695,-.016939,
-.013,-.017,
.013,-.017,
.013695,-.016939,
.014368,-.016759,
.015,-.016464,
.015571,-.016064,
.016064,-.015571,
.016464,-.015,
.016759,-.014368,
.016939,-.013695,
.017,-.013,
.017,.013,
.016939,.013695,
.016759,.014368,
.016464,.015,
.016064,.015571,
.015571,.016064,
.015,.016464,
.014368,.016759,
.013695,.016939,
.013,.017,
-.013,.017,
-.013695,.016939,
-.014368,.016759,
-.015,.016464,
-.015571,.016064,
-.016064,.015571,
-.016464,.015,
-.016759,.014368,
-.016939,.013695,
-.017,.013,
0.0*
%
%ADD58MACRO58*%
%ADD80R,.06X.02*%
%ADD18R,.06X.012*%
%AMMACRO71*
4,1,12,.1525,.07,
.1525,-.07,
.0725,-.07,
.0725,-.015,
-.0725,-.015,
-.0725,-.025,
-.1525,-.025,
-.1525,.025,
-.0725,.025,
-.0725,.015,
.0725,.015,
.0725,.07,
.1525,.07,
0.0*
%
%ADD71MACRO71*%
%ADD43O,.071X.014*%
%ADD86R,.04X.016*%
%ADD84R,.06X.014*%
%ADD63R,.044X.012*%
%ADD89R,.014X.042*%
%ADD88R,.042X.014*%
%ADD79R,.014X.06*%
%ADD32R,.045X.03*%
%ADD70R,.08X.05*%
%ADD67R,.038X.012*%
%ADD66R,.012X.038*%
%ADD52R,.124X.138*%
%ADD90R,.05X.065*%
%ADD55R,.252X.228*%
%ADD73R,.073X.07*%
%ADD46R,.065X.05*%
%ADD85R,.065X.025*%
%ADD81R,.09X.09*%
%ADD51R,.025X.065*%
%ADD37R,.045X.055*%
%ADD75R,.083X.035*%
%ADD72R,.081X.065*%
%ADD64R,.074X.054*%
%ADD41R,.055X.045*%
%ADD33R,.016X.048*%
%ADD74R,.073X.065*%
%ADD54R,.065X.081*%
%ADD62C,.158*%
%ADD50R,.095X.09*%
%ADD17C,.375*%
%ADD27R,.038X.095*%
%ADD56R,.087X.047*%
%ADD87R,.128X.128*%
%AMMACRO68*
4,1,12,-.0425,.0425,
-.015,.0425,
-.015,.072,
.015,.072,
.015,.0425,
.0425,.0425,
.0425,-.0425,
.015,-.0425,
.015,-.072,
-.015,-.072,
-.015,-.0425,
-.0425,-.0425,
-.0425,.0425,
0.0*
%
%ADD68MACRO68*%
%AMMACRO40*
4,1,40,-.008,-.012,
.008,-.012,
.008695,-.011939,
.009368,-.011759,
.01,-.011464,
.010571,-.011064,
.011064,-.010571,
.011464,-.01,
.011759,-.009368,
.011939,-.008695,
.012,-.008,
.012,.008,
.011939,.008695,
.011759,.009368,
.011464,.01,
.011064,.010571,
.010571,.011064,
.01,.011464,
.009368,.011759,
.008695,.011939,
.008,.012,
-.008,.012,
-.008695,.011939,
-.009368,.011759,
-.01,.011464,
-.010571,.011064,
-.011064,.010571,
-.011464,.01,
-.011759,.009368,
-.011939,.008695,
-.012,.008,
-.012,-.008,
-.011939,-.008695,
-.011759,-.009368,
-.011464,-.01,
-.011064,-.010571,
-.010571,-.011064,
-.01,-.011464,
-.009368,-.011759,
-.008695,-.011939,
-.008,-.012,
0.0*
%
%ADD40MACRO40*%
%AMMACRO28*
4,1,40,.012,-.008,
.012,.008,
.011939,.008695,
.011759,.009368,
.011464,.01,
.011064,.010571,
.010571,.011064,
.01,.011464,
.009368,.011759,
.008695,.011939,
.008,.012,
-.008,.012,
-.008695,.011939,
-.009368,.011759,
-.01,.011464,
-.010571,.011064,
-.011064,.010571,
-.011464,.01,
-.011759,.009368,
-.011939,.008695,
-.012,.008,
-.012,-.008,
-.011939,-.008695,
-.011759,-.009368,
-.011464,-.01,
-.011064,-.010571,
-.010571,-.011064,
-.01,-.011464,
-.009368,-.011759,
-.008695,-.011939,
-.008,-.012,
.008,-.012,
.008695,-.011939,
.009368,-.011759,
.01,-.011464,
.010571,-.011064,
.011064,-.010571,
.011464,-.01,
.011759,-.009368,
.011939,-.008695,
.012,-.008,
0.0*
%
%ADD28MACRO28*%
%AMMACRO21*
4,1,40,-.007,-.011,
.007,-.011,
.007695,-.010939,
.008368,-.010759,
.009,-.010464,
.009571,-.010064,
.010064,-.009571,
.010464,-.009,
.010759,-.008368,
.010939,-.007695,
.011,-.007,
.011,.007,
.010939,.007695,
.010759,.008368,
.010464,.009,
.010064,.009571,
.009571,.010064,
.009,.010464,
.008368,.010759,
.007695,.010939,
.007,.011,
-.007,.011,
-.007695,.010939,
-.008368,.010759,
-.009,.010464,
-.009571,.010064,
-.010064,.009571,
-.010464,.009,
-.010759,.008368,
-.010939,.007695,
-.011,.007,
-.011,-.007,
-.010939,-.007695,
-.010759,-.008368,
-.010464,-.009,
-.010064,-.009571,
-.009571,-.010064,
-.009,-.010464,
-.008368,-.010759,
-.007695,-.010939,
-.007,-.011,
0.0*
%
%ADD21MACRO21*%
%AMMACRO19*
4,1,40,-.011,.007,
-.011,-.007,
-.010939,-.007695,
-.010759,-.008368,
-.010464,-.009,
-.010064,-.009571,
-.009571,-.010064,
-.009,-.010464,
-.008368,-.010759,
-.007695,-.010939,
-.007,-.011,
.007,-.011,
.007695,-.010939,
.008368,-.010759,
.009,-.010464,
.009571,-.010064,
.010064,-.009571,
.010464,-.009,
.010759,-.008368,
.010939,-.007695,
.011,-.007,
.011,.007,
.010939,.007695,
.010759,.008368,
.010464,.009,
.010064,.009571,
.009571,.010064,
.009,.010464,
.008368,.010759,
.007695,.010939,
.007,.011,
-.007,.011,
-.007695,.010939,
-.008368,.010759,
-.009,.010464,
-.009571,.010064,
-.010064,.009571,
-.010464,.009,
-.010759,.008368,
-.010939,.007695,
-.011,.007,
0.0*
%
%ADD19MACRO19*%
%AMMACRO78*
4,1,6,.025,.0135,
.005,-.0065,
.005,-.0135,
-.005,-.0135,
-.005,-.0065,
-.025,.0135,
.025,.0135,
0.0*
%
%ADD78MACRO78*%
%AMMACRO48*
4,1,40,.017,-.013,
.017,.013,
.016939,.013695,
.016759,.014368,
.016464,.015,
.016064,.015571,
.015571,.016064,
.015,.016464,
.014368,.016759,
.013695,.016939,
.013,.017,
-.013,.017,
-.013695,.016939,
-.014368,.016759,
-.015,.016464,
-.015571,.016064,
-.016064,.015571,
-.016464,.015,
-.016759,.014368,
-.016939,.013695,
-.017,.013,
-.017,-.013,
-.016939,-.013695,
-.016759,-.014368,
-.016464,-.015,
-.016064,-.015571,
-.015571,-.016064,
-.015,-.016464,
-.014368,-.016759,
-.013695,-.016939,
-.013,-.017,
.013,-.017,
.013695,-.016939,
.014368,-.016759,
.015,-.016464,
.015571,-.016064,
.016064,-.015571,
.016464,-.015,
.016759,-.014368,
.016939,-.013695,
.017,-.013,
0.0*
%
%ADD48MACRO48*%
%AMMACRO31*
4,1,40,.013,.017,
-.013,.017,
-.013695,.016939,
-.014368,.016759,
-.015,.016464,
-.015571,.016064,
-.016064,.015571,
-.016464,.015,
-.016759,.014368,
-.016939,.013695,
-.017,.013,
-.017,-.013,
-.016939,-.013695,
-.016759,-.014368,
-.016464,-.015,
-.016064,-.015571,
-.015571,-.016064,
-.015,-.016464,
-.014368,-.016759,
-.013695,-.016939,
-.013,-.017,
.013,-.017,
.013695,-.016939,
.014368,-.016759,
.015,-.016464,
.015571,-.016064,
.016064,-.015571,
.016464,-.015,
.016759,-.014368,
.016939,-.013695,
.017,-.013,
.017,.013,
.016939,.013695,
.016759,.014368,
.016464,.015,
.016064,.015571,
.015571,.016064,
.015,.016464,
.014368,.016759,
.013695,.016939,
.013,.017,
0.0*
%
%ADD31MACRO31*%
%AMMACRO69*
4,1,6,-.005,-.0135,
-.005,-.0065,
-.025,.0135,
.025,.0135,
.005,-.0065,
.005,-.0135,
-.005,-.0135,
0.0*
%
%ADD69MACRO69*%
%AMMACRO39*
4,1,40,-.008,-.012,
.008,-.012,
.008695,-.011939,
.009368,-.011759,
.01,-.011464,
.010571,-.011064,
.011064,-.010571,
.011464,-.01,
.011759,-.009368,
.011939,-.008695,
.012,-.008,
.012,.008,
.011939,.008695,
.011759,.009368,
.011464,.01,
.011064,.010571,
.010571,.011064,
.01,.011464,
.009368,.011759,
.008695,.011939,
.008,.012,
-.008,.012,
-.008695,.011939,
-.009368,.011759,
-.01,.011464,
-.010571,.011064,
-.011064,.010571,
-.011464,.01,
-.011759,.009368,
-.011939,.008695,
-.012,.008,
-.012,-.008,
-.011939,-.008695,
-.011759,-.009368,
-.011464,-.01,
-.011064,-.010571,
-.010571,-.011064,
-.01,-.011464,
-.009368,-.011759,
-.008695,-.011939,
-.008,-.012,
0.0*
%
%ADD39MACRO39*%
%AMMACRO38*
4,1,40,.012,-.008,
.012,.008,
.011939,.008695,
.011759,.009368,
.011464,.01,
.011064,.010571,
.010571,.011064,
.01,.011464,
.009368,.011759,
.008695,.011939,
.008,.012,
-.008,.012,
-.008695,.011939,
-.009368,.011759,
-.01,.011464,
-.010571,.011064,
-.011064,.010571,
-.011464,.01,
-.011759,.009368,
-.011939,.008695,
-.012,.008,
-.012,-.008,
-.011939,-.008695,
-.011759,-.009368,
-.011464,-.01,
-.011064,-.010571,
-.010571,-.011064,
-.01,-.011464,
-.009368,-.011759,
-.008695,-.011939,
-.008,-.012,
.008,-.012,
.008695,-.011939,
.009368,-.011759,
.01,-.011464,
.010571,-.011064,
.011064,-.010571,
.011464,-.01,
.011759,-.009368,
.011939,-.008695,
.012,-.008,
0.0*
%
%ADD38MACRO38*%
%AMMACRO22*
4,1,40,-.007,-.011,
.007,-.011,
.007695,-.010939,
.008368,-.010759,
.009,-.010464,
.009571,-.010064,
.010064,-.009571,
.010464,-.009,
.010759,-.008368,
.010939,-.007695,
.011,-.007,
.011,.007,
.010939,.007695,
.010759,.008368,
.010464,.009,
.010064,.009571,
.009571,.010064,
.009,.010464,
.008368,.010759,
.007695,.010939,
.007,.011,
-.007,.011,
-.007695,.010939,
-.008368,.010759,
-.009,.010464,
-.009571,.010064,
-.010064,.009571,
-.010464,.009,
-.010759,.008368,
-.010939,.007695,
-.011,.007,
-.011,-.007,
-.010939,-.007695,
-.010759,-.008368,
-.010464,-.009,
-.010064,-.009571,
-.009571,-.010064,
-.009,-.010464,
-.008368,-.010759,
-.007695,-.010939,
-.007,-.011,
0.0*
%
%ADD22MACRO22*%
%AMMACRO20*
4,1,40,-.011,.007,
-.011,-.007,
-.010939,-.007695,
-.010759,-.008368,
-.010464,-.009,
-.010064,-.009571,
-.009571,-.010064,
-.009,-.010464,
-.008368,-.010759,
-.007695,-.010939,
-.007,-.011,
.007,-.011,
.007695,-.010939,
.008368,-.010759,
.009,-.010464,
.009571,-.010064,
.010064,-.009571,
.010464,-.009,
.010759,-.008368,
.010939,-.007695,
.011,-.007,
.011,.007,
.010939,.007695,
.010759,.008368,
.010464,.009,
.010064,.009571,
.009571,.010064,
.009,.010464,
.008368,.010759,
.007695,.010939,
.007,.011,
-.007,.011,
-.007695,.010939,
-.008368,.010759,
-.009,.010464,
-.009571,.010064,
-.010064,.009571,
-.010464,.009,
-.010759,.008368,
-.010939,.007695,
-.011,.007,
0.0*
%
%ADD20MACRO20*%
%ADD93C,.03*%
%ADD94C,.012*%
%ADD95C,.04*%
%ADD96C,.014*%
%ADD97C,.015*%
%ADD98C,.016*%
%ADD99C,.025*%
%ADD100C,.004*%
%ADD101C,.006*%
%ADD114R,.019X.008*%
%ADD107C,.05204*%
%ADD104C,.04604*%
%ADD109C,.08504*%
%ADD112R,.01953X.008*%
%ADD113R,.01864X.008*%
%ADD110R,.01954X.008*%
%ADD105C,.07904*%
%ADD111R,.01974X.008*%
%ADD106R,.13204X.13204*%
%ADD103C,.10306*%
%ADD108R,.008X.008*%
%ADD102C,.18206*%
G75*
%LPD*%
G75*
G36*
G01X383987Y122852D02*
X380588Y126250D01*
Y140612D01*
X378300Y142900D01*
X225500D01*
X224200Y144200D01*
Y149533D01*
X223300Y150433D01*
X212162D01*
X211227Y149498D01*
Y144188D01*
X209239Y142200D01*
X200626D01*
X200613Y142213D01*
X199187D01*
X198800Y142600D01*
Y150500D01*
X198000Y151300D01*
X193800D01*
X193000Y152100D01*
Y160360D01*
X193700Y161060D01*
X208340D01*
X210281Y159119D01*
X222658D01*
X223724Y160185D01*
Y167976D01*
X222450Y169250D01*
X215650D01*
X215102Y169798D01*
Y173898D01*
X215100Y173899D01*
Y174100D01*
X213700Y175500D01*
X210700D01*
X210300Y175900D01*
Y181400D01*
X207300Y184400D01*
X192500D01*
X190302Y186598D01*
Y232900D01*
X191604Y234202D01*
Y249736D01*
X191693Y249825D01*
X197000D01*
X197300Y249525D01*
Y248200D01*
X198100Y247400D01*
X201600D01*
X202800Y248600D01*
Y250025D01*
X202801Y250035D01*
G03Y250631I-2786J298D01*
G01X202800Y250641D01*
Y252784D01*
X198942Y256642D01*
Y273589D01*
X198947Y273611D01*
G03Y274855I-2732J622D01*
G01X198942Y274877D01*
Y275558D01*
X196000Y278500D01*
Y283900D01*
X193557Y286343D01*
X191264D01*
X185476Y292131D01*
X184090D01*
X184074Y292134D01*
G03X183362Y292137I-366J-2273D01*
G01X183262Y292122D01*
X182292Y293092D01*
X182302Y293188D01*
G03X182312Y293361I-1592J179D01*
G01Y294761D01*
G03X182284Y295054I-1602J-5D01*
G01X182281Y295073D01*
Y295353D01*
X182128Y295506D01*
X182114Y295531D01*
G03X181480Y296165I-1404J-770D01*
G01X181455Y296179D01*
X181220Y296414D01*
X175224D01*
X174906Y296096D01*
X164439D01*
X164389Y296128D01*
G03X161895I-1247J-1935D01*
G01X161845Y296096D01*
X155577D01*
X145743Y286262D01*
X136454D01*
X135956Y286760D01*
X123556D01*
X117393Y292924D01*
X112181D01*
X112129Y292960D01*
G03X109487I-1321J-1885D01*
G01X109435Y292924D01*
X106998D01*
X106946Y292962D01*
G03X104260I-1343J-1870D01*
G01X104208Y292924D01*
X96401D01*
X96354Y292951D01*
G03X94050I-1152J-1993D01*
G01X94003Y292924D01*
X79524D01*
X79048Y292448D01*
X72984D01*
X67907Y297525D01*
X57280D01*
X49864Y290109D01*
Y246164D01*
X48100Y244400D01*
Y241236D01*
X54979Y234357D01*
Y206500D01*
X63200Y198279D01*
Y181500D01*
X67500Y177200D01*
Y176896D01*
Y176892D01*
G03Y176708I2300J-92D01*
G01Y176704D01*
Y175400D01*
X69000Y173900D01*
X71500D01*
X72200Y174600D01*
Y179931D01*
Y179935D01*
G03X72202Y180000I-1599J82D01*
G01Y181600D01*
G03X72200Y181665I-1601J-17D01*
G01Y181669D01*
Y182000D01*
X73648Y183448D01*
X73662D01*
Y183462D01*
X74200Y184000D01*
Y188700D01*
X74906Y189406D01*
X74975Y189414D01*
G03X74976Y193985I-275J2286D01*
G01X74800Y194007D01*
Y197100D01*
X72600Y199300D01*
Y200500D01*
X71500Y201600D01*
X70296D01*
X70292D01*
G03X70108I-92J-2300D01*
G01X70104D01*
X67700D01*
X67200Y202100D01*
Y208400D01*
X68000Y209200D01*
X75400D01*
X78400Y206200D01*
Y200669D01*
Y200665D01*
G03X78398Y200600I1599J-82D01*
G01Y199000D01*
G03X78400Y198935I1601J17D01*
G01Y198931D01*
Y192677D01*
X78399Y192666D01*
G03Y192130I2286J-268D01*
G01X78400Y192119D01*
Y191200D01*
X80105Y189495D01*
Y182795D01*
X80850Y182050D01*
X85250D01*
X86300Y183100D01*
Y185848D01*
X87061Y186609D01*
X111600D01*
X112059Y186150D01*
Y181041D01*
X113345Y179755D01*
X117106D01*
X117166Y179685D01*
G03X120270Y178871I2135J1815D01*
G01X120390Y178916D01*
X121873Y177433D01*
Y170339D01*
X127156Y165056D01*
Y149700D01*
X126569Y149113D01*
X96714D01*
X96128Y149699D01*
Y154751D01*
X95583Y155296D01*
X95572Y155359D01*
G03X91947Y156830I-2269J-389D01*
G01X91895Y156792D01*
X89600D01*
X88504Y155696D01*
X76404D01*
X74400Y157700D01*
Y162100D01*
X73800Y162700D01*
X67700D01*
X66500Y161500D01*
Y124700D01*
X62400Y120600D01*
X26700D01*
X19450Y113350D01*
Y107415D01*
X19441Y107386D01*
G03Y105212I3539J-1087D01*
G01X19450Y105183D01*
Y99541D01*
X19441Y99512D01*
G03Y97338I3539J-1087D01*
G01X19450Y97309D01*
Y96877D01*
X17898Y95326D01*
Y87719D01*
X19450Y86168D01*
Y83793D01*
X19441Y83764D01*
G03Y81590I3539J-1087D01*
G01X19450Y81561D01*
Y75919D01*
X19441Y75890D01*
G03Y73716I3539J-1087D01*
G01X19450Y73687D01*
Y68045D01*
X19441Y68016D01*
G03Y65842I3539J-1087D01*
G01X19450Y65813D01*
Y60171D01*
X19441Y60142D01*
G03Y57968I3539J-1087D01*
G01X19450Y57939D01*
Y56350D01*
X21100Y54700D01*
X34500D01*
X36900Y52300D01*
Y42000D01*
X48100Y30800D01*
X59469D01*
G02X59809Y30189I0J-400D01*
G03X64548Y3916I16963J-10504D01*
G02X64303Y3200I-245J-316D01*
G01X41997D01*
G02X41752Y3916I0J400D01*
G03X17304I-12224J15769D01*
G02X17059Y3200I-245J-316D01*
G01X4200D01*
X3200Y4200D01*
Y211700D01*
X-900Y215800D01*
X-139900D01*
X-140600Y216500D01*
Y338800D01*
X-140100Y339300D01*
X-62400D01*
X-60700Y339800D01*
X-59300Y340400D01*
X-57700Y341800D01*
X-56500Y343600D01*
X-56100Y344900D01*
X-56000Y345300D01*
Y504100D01*
X-55300Y504800D01*
X-3400D01*
X-1500Y505100D01*
X700Y506400D01*
X2300Y508400D01*
X3100Y510900D01*
Y542800D01*
X4500Y544200D01*
X19000D01*
X20200Y543000D01*
Y514300D01*
X1100Y495200D01*
Y281573D01*
G02X337Y281404I-400J0D01*
G03Y273714I-8250J-3845D01*
G02X1100Y273545I363J-169D01*
G01Y228500D01*
X14000Y215600D01*
Y150200D01*
X33900Y130300D01*
X43500D01*
X45800Y132600D01*
Y169700D01*
X46200Y170100D01*
Y173600D01*
X46500Y173900D01*
X53900D01*
X54235Y174235D01*
G02X54875Y174132I283J-283D01*
G03X57829Y177825I2325J1168D01*
G01X57775Y177838D01*
X56112Y179502D01*
X51948D01*
X51900Y179550D01*
X37550D01*
X36600Y180500D01*
Y201860D01*
X6961Y231500D01*
Y332461D01*
G02X7640Y332748I400J0D01*
G03Y336052I1603J1652D01*
G02X6961Y336339I-279J287D01*
G01Y364834D01*
X9180Y367053D01*
Y369532D01*
X12828Y373180D01*
X39158D01*
X46770Y365568D01*
X60000D01*
X60568Y365000D01*
X62700D01*
X63900Y366200D01*
Y371900D01*
X64000Y372000D01*
X64820D01*
X64834Y371998D01*
G03X65063Y371982I226J1585D01*
G01X66463D01*
G03X66692Y371998I3J1601D01*
G01X66706Y372000D01*
X67366D01*
X69267Y370098D01*
X74681D01*
X77116Y372534D01*
Y377513D01*
X80991Y381388D01*
X98041D01*
X100540Y378889D01*
Y363108D01*
X115291Y348357D01*
Y335930D01*
X115280Y335899D01*
G03Y334417I2180J-741D01*
G01X115291Y334386D01*
Y332774D01*
X115287Y332754D01*
G03X115254Y332429I1568J-323D01*
G01Y331029D01*
G03X115287Y330704I1601J-2D01*
G01X115291Y330684D01*
Y321473D01*
X119494Y317270D01*
X123986D01*
X124043Y317218D01*
G03X127911Y314044I33709J37135D01*
G01X127923Y314035D01*
X131527Y310431D01*
X133541D01*
X133586Y310406D01*
G03X138012Y308248I24166J43947D01*
G01X138048Y308233D01*
X141699Y304582D01*
X151577D01*
X151590Y304580D01*
G03X157752Y304200I6162J49773D01*
G01X189268D01*
X189341Y304127D01*
X189403Y304189D01*
X214100D01*
X220131Y298158D01*
Y293003D01*
X222030Y291104D01*
X659229D01*
X696658Y328533D01*
X754342D01*
X756028Y326847D01*
Y3928D01*
X755300Y3200D01*
X89241D01*
G02X88996Y3916I0J400D01*
G03X93704Y30238I-12224J15768D01*
G02X94044Y30850I340J212D01*
G01X94150D01*
X95400Y32100D01*
Y57500D01*
X96644Y58744D01*
X174444D01*
X176487Y56700D01*
Y47587D01*
X178213Y45861D01*
X212839D01*
X215678Y48700D01*
Y53767D01*
X217159Y55248D01*
X220974D01*
X223046Y57320D01*
Y62348D01*
X223479Y62781D01*
X223911D01*
X223922Y62770D01*
X224127D01*
X224151Y62764D01*
G03X224531Y62718I381J1556D01*
G01X225931D01*
G03X226311Y62764I-1J1602D01*
G01X226335Y62770D01*
X226960D01*
X227169Y62562D01*
Y57321D01*
X228560Y55930D01*
X267766D01*
X268536Y55160D01*
Y42131D01*
X272208Y38459D01*
X293468D01*
X303427Y28500D01*
X379000D01*
X382777Y32277D01*
Y54700D01*
X380877Y56600D01*
X298800D01*
X297900Y57500D01*
Y69300D01*
X298800Y70200D01*
X382676D01*
X382788Y70312D01*
X383800Y71323D01*
Y80000D01*
X380094Y83706D01*
X260600D01*
X260540Y83775D01*
G03X259330Y84328I-1211J-1049D01*
G01X257730D01*
G03X256128Y82726I0J-1602D01*
G01Y81126D01*
G03X256184Y80709I1602J3D01*
G01X256214Y80598D01*
X255632Y80016D01*
X250636D01*
X250147Y80506D01*
Y85947D01*
X250600Y86400D01*
X253526D01*
X253564Y86383D01*
G03X256260Y89968I934J2104D01*
G01X256213Y90024D01*
Y92287D01*
X258067Y94141D01*
Y101031D01*
X249306Y109792D01*
X244134D01*
X243484Y110442D01*
Y116970D01*
X244112Y117598D01*
X381087D01*
X381937Y118448D01*
X722014D01*
X722041Y118440D01*
G03Y122860I646J2210D01*
G01X722014Y122852D01*
X383987D01*
G37*
G36*
G01X52000Y33700D02*
X51975Y33725D01*
X49475D01*
X40400Y42800D01*
Y78200D01*
X42100Y79900D01*
X56500D01*
X57800Y81200D01*
X79800D01*
X83099Y84499D01*
X106239D01*
X106285Y84472D01*
G03X107083Y84260I796J1389D01*
G01X108483D01*
G03X109281Y84472I2J1601D01*
G01X109327Y84499D01*
X115499D01*
X146100Y115100D01*
X170600D01*
X171124Y114576D01*
Y61524D01*
X170200Y60600D01*
X94400D01*
X93300Y59500D01*
Y35976D01*
G02X92619Y35692I-400J0D01*
G03X59199Y33775I-15847J-16007D01*
G01X59139Y33700D01*
X52000D01*
G37*
G36*
G01X31053Y475125D02*
X30287Y475891D01*
Y489946D01*
X28800Y491433D01*
Y494086D01*
X28688Y494198D01*
Y494211D01*
X26790Y496110D01*
Y496286D01*
Y496291D01*
G03X26792Y496366I-1600J80D01*
G01Y497966D01*
G03X26779Y498165I-1602J-5D01*
G01X26778Y498178D01*
Y499473D01*
X26774Y499477D01*
Y502180D01*
X27738Y503144D01*
X29661D01*
X29688Y503117D01*
X36609D01*
X36993Y503501D01*
X45900D01*
X46850Y502550D01*
Y496662D01*
X44188Y494000D01*
X42400D01*
X40600Y492200D01*
Y488964D01*
X41441Y488123D01*
Y481359D01*
X41450Y481350D01*
Y475600D01*
X40975Y475125D01*
X31053D01*
G37*
G36*
G01X15329Y474562D02*
X12209Y477682D01*
Y496533D01*
X15463Y499787D01*
X20181D01*
X20196Y499772D01*
X24781D01*
X25576Y498976D01*
Y495800D01*
X25588Y495788D01*
Y495612D01*
X27487Y493713D01*
Y490766D01*
X28434Y489819D01*
Y474948D01*
X28048Y474562D01*
X25625D01*
X25575Y474595D01*
G03X23055I-1260J-1927D01*
G01X23005Y474562D01*
X15329D01*
G37*
G36*
G01X30978Y504686D02*
X30606Y505058D01*
Y511806D01*
X34400Y515600D01*
Y517700D01*
X32181Y519919D01*
Y527681D01*
X32700Y528200D01*
X35500D01*
X37350Y526350D01*
X39814D01*
X41502Y524662D01*
Y514537D01*
X45428Y510611D01*
X45441Y510554D01*
G03X45738Y509529I7951J1748D01*
G01X45750Y509496D01*
Y505833D01*
X44620Y504702D01*
X36495D01*
X36479Y504686D01*
X30978D01*
G37*
G36*
G01X83500Y102083D02*
X79600Y105983D01*
Y122167D01*
X80200Y122767D01*
X89924D01*
X95229Y117462D01*
X118938D01*
X120100Y116300D01*
Y106600D01*
X115583Y102083D01*
X83500D01*
G37*
G36*
G01X150049Y131188D02*
X145930Y127070D01*
X142870D01*
X136382Y120582D01*
X94188D01*
X85500Y129270D01*
Y136788D01*
X86300Y137588D01*
X88625D01*
X90578Y139541D01*
Y146104D01*
X90587Y146113D01*
Y147187D01*
X91197Y147797D01*
X127203D01*
X128050Y146950D01*
Y142250D01*
X129500Y140800D01*
X149000D01*
X150061Y139739D01*
Y131329D01*
X150060Y131318D01*
G03X150055Y131262I2290J-233D01*
G01X150049Y131188D01*
G37*
G36*
G01X130487Y164367D02*
X123265Y171589D01*
Y183443D01*
X121666Y185042D01*
X118690D01*
X117400Y186332D01*
Y188600D01*
X116700Y189300D01*
X114067D01*
X113567Y189800D01*
Y191634D01*
X114200Y192267D01*
X116177D01*
X116204Y192259D01*
G03X116641Y192198I438J1541D01*
G01X118041D01*
G03X118478Y192259I-1J1602D01*
G01X118505Y192267D01*
X119577D01*
X119604Y192259D01*
G03X120041Y192198I438J1541D01*
G01X121441D01*
G03X121859Y192254I-2J1602D01*
G01X121885Y192261D01*
X133802D01*
X134840Y191223D01*
Y186219D01*
X142205Y178854D01*
Y175105D01*
X143504Y173806D01*
X144631D01*
X144663Y173774D01*
X147830D01*
X147845Y173789D01*
X149809D01*
X150530Y173068D01*
Y171215D01*
X145013D01*
X144050Y170252D01*
X143294D01*
X143271Y170257D01*
G03X140042Y166423I-656J-2724D01*
G01X140096Y166298D01*
X138165Y164367D01*
X130487D01*
G37*
G36*
G01X131600Y144400D02*
X130400Y145600D01*
Y159100D01*
X131833Y160533D01*
X143587D01*
X143647Y160463D01*
G03X147153I1753J1492D01*
G01X147213Y160533D01*
X154881D01*
X156749Y158664D01*
X156768D01*
X157133Y158300D01*
X157258D01*
Y158264D01*
X161898D01*
Y155962D01*
X157258D01*
X156867Y155571D01*
Y153665D01*
X156540Y153338D01*
X153050D01*
X151056Y151344D01*
Y146456D01*
X149000Y144400D01*
X131600D01*
G37*
G36*
G01X168900Y182200D02*
X141078D01*
X137500Y185778D01*
Y206800D01*
X138100Y207400D01*
X158200D01*
X159300Y208500D01*
Y230000D01*
X160000Y230700D01*
X169800D01*
X171900Y228600D01*
Y219822D01*
X183722Y208000D01*
Y183922D01*
X182700Y182900D01*
X169600D01*
X168900Y182200D01*
G37*
G36*
G01X129100Y215400D02*
X127900Y216600D01*
Y221104D01*
Y221108D01*
G03Y221292I-2300J92D01*
G01Y221296D01*
Y224522D01*
X127908Y224549D01*
G03Y225851I-2208J651D01*
G01X127900Y225878D01*
Y235600D01*
X128600Y236300D01*
X145100D01*
X145800Y235600D01*
Y234769D01*
Y234765D01*
G03X145798Y234700I1599J-82D01*
G01Y233100D01*
G03X145800Y233035I1601J17D01*
G01Y233031D01*
Y230100D01*
X144300Y228600D01*
Y215900D01*
X143800Y215400D01*
X129100D01*
G37*
G36*
G01X124713Y407922D02*
X123962Y407170D01*
Y406366D01*
X123784Y406346D01*
G03X122366Y405554I236J-2089D01*
G02X121737I-315J247D01*
G03X118429I-1654J-1297D01*
G02X117799I-315J247D01*
G03X117454Y405902I-1655J-1296D01*
G02X117420Y406497I249J313D01*
G01X117631Y406708D01*
G03X114659Y409680I-1486J1486D01*
G01X112689Y407710D01*
G03X112078Y406355I1486J-1485D01*
G03X110554Y405554I130J-2098D01*
G02X109925I-314J247D01*
G03X109580Y405902I-1655J-1296D01*
G02X109546Y406497I249J313D01*
G01X109757Y406708D01*
G03X110368Y408064I-1486J1485D01*
G03X111724Y408675I-129J2097D01*
G01X113694Y410645D01*
G03X114305Y412001I-1486J1485D01*
G03X115661Y412612I-129J2097D01*
G01X117631Y414582D01*
G03X117799Y414772I-1487J1484D01*
G02X118429I315J-247D01*
G03X118597Y414582I1655J1294D01*
G01X119080Y414100D01*
X118597Y413617D01*
G03X121569Y410645I1486J-1486D01*
G01X121780Y410856D01*
G02X122376Y410822I283J-283D01*
G03X122534Y410645I1644J1309D01*
G01X124504Y408675D01*
G03X124680Y408518I1485J1487D01*
G02X124713Y407922I-249J-313D01*
G37*
G36*
G01X115549Y431365D02*
X114571Y432343D01*
G02X114854Y433026I283J283D01*
G01X117141D01*
X117790Y432377D01*
Y431381D01*
X118129Y431042D01*
X118144Y431006D01*
G03X118597Y430330I1939J810D01*
G01X120567Y428360D01*
G03X123166Y428064I1486J1486D01*
G01X123215Y428094D01*
X123611D01*
X125232Y429714D01*
X127957D01*
G03X129702Y430644I0J2102D01*
G01X129761Y430733D01*
X130090D01*
X130149Y430644D01*
G03X130408Y430330I1743J1174D01*
G01X132719Y428019D01*
Y427517D01*
X132644Y427457D01*
G03X132074Y426755I1308J-1645D01*
G01X132060Y426726D01*
X131289Y425955D01*
X131244Y425940D01*
G03X130408Y422456I650J-1998D01*
G01X134345Y418519D01*
G03X134942Y418101I1486J1486D01*
G01X134974Y418086D01*
X137849Y415211D01*
X137864Y415179D01*
G03X138282Y414582I1904J889D01*
G01X140252Y412612D01*
G03X140849Y412194I1486J1486D01*
G01X140881Y412179D01*
X141786Y411274D01*
X141801Y411242D01*
G03X142578Y410357I1904J888D01*
G01X142671Y410298D01*
Y410027D01*
X142578Y409968D01*
G03X142061Y409503I1128J-1774D01*
G02X141465Y409469I-313J249D01*
G01X141254Y409680D01*
G03X138282Y406708I-1486J-1486D01*
G01X138493Y406497D01*
G02X138459Y405902I-283J-282D01*
G03X138114Y405554I1310J-1644D01*
G02X137485I-315J247D01*
G03X134177I-1654J-1297D01*
G02X133548I-314J247D01*
G03X130240I-1654J-1297D01*
G02X129611I-315J247D01*
G03X129266Y405902I-1655J-1296D01*
G02X129232Y406497I249J313D01*
G01X129443Y406708D01*
G03X129267Y409837I-1486J1486D01*
G02X129234Y410433I249J313D01*
G01X130058Y411258D01*
Y412131D01*
G03X126409Y413552I-2101J0D01*
G01X126406Y413549D01*
X125990Y413133D01*
X125506Y413617D01*
G03X124150Y414228I-1485J-1486D01*
G03X123539Y415584I-2097J-129D01*
G01X121569Y417554D01*
G03X118429Y417364I-1486J-1486D01*
G02X117799I-315J247D01*
G03X114659Y417554I-1654J-1296D01*
G01X112689Y415584D01*
G03X112078Y414228I1486J-1485D01*
G03X110722Y413617I129J-2097D01*
G01X110238Y413133D01*
X109822Y413549D01*
X109819Y413552D01*
G03X106170Y412131I-1548J-1421D01*
G01Y411258D01*
X106994Y410433D01*
G02X106961Y409837I-282J-283D01*
G03X106785Y409680I1309J-1644D01*
G01X104815Y407710D01*
G03X104204Y406355I1486J-1485D01*
G03X102680Y405554I130J-2098D01*
G02X102051I-314J247D01*
G03X98743I-1654J-1297D01*
G02X98114I-314J247D01*
G03X97769Y405902I-1655J-1296D01*
G02X97735Y406497I249J313D01*
G01X97946Y406708D01*
G03X98557Y408064I-1486J1485D01*
G03X99913Y408675I-129J2097D01*
G01X101883Y410645D01*
G03X98911Y413617I-1486J1486D01*
G01X98685Y413391D01*
X98169D01*
X98011Y413549D01*
X98008Y413552D01*
G03X94358Y412131I-1548J-1421D01*
G01Y411736D01*
X92888Y410266D01*
X92790Y410278D01*
G03X90439Y407927I-267J-2084D01*
G01X90451Y407829D01*
X89881Y407258D01*
X87749D01*
X87508Y407500D01*
Y409102D01*
X88439Y410033D01*
X88525Y410030D01*
G03X90072Y410645I61J2101D01*
G01X94009Y414582D01*
G03X94624Y416059I-1486J1485D01*
G03X95956Y416884I-361J2070D01*
G02X96561Y416929I322J-237D01*
G01X97412Y416078D01*
X99442D01*
X101883Y418519D01*
G03X101717Y421640I-1486J1486D01*
G02X101686Y422234I252J311D01*
G01X102333Y422881D01*
X104724Y420490D01*
G03X107900Y420727I1486J1486D01*
G02X108504Y420772I321J-238D01*
G01X109433Y419843D01*
G02X109376Y419230I-283J-283D01*
G03X111706Y417755I846J-1241D01*
G02X111930Y417922I197J-31D01*
G03X114310Y420005I278J2083D01*
G01Y420910D01*
X112464Y422755D01*
Y422909D01*
X111712Y423662D01*
G02X111729Y424244I283J283D01*
G03X111818Y427300I-1397J1570D01*
G01X109832Y429286D01*
X109829Y429290D01*
G03X109568Y429533I-1558J-1411D01*
G02Y430162I247J315D01*
G03X109884Y430469I-1298J1653D01*
G02X110474Y430496I307J-256D01*
G01X112577Y428393D01*
G03X115549Y431365I1486J1486D01*
G37*
G36*
G01X130252Y441017D02*
X126539Y437304D01*
X126536Y437301D01*
G03X126146Y434687I1421J-1548D01*
G01X126224Y434554D01*
X125850Y434180D01*
X122719D01*
X122320Y434579D01*
Y435015D01*
X126122Y438817D01*
Y439690D01*
G03X122472Y441111I-2102J0D01*
G01X122469Y441108D01*
X118665Y437304D01*
X118662Y437301D01*
G03X118102Y435052I1421J-1548D01*
G01X118144Y434933D01*
X117797Y434586D01*
X115655D01*
X114834Y435407D01*
X117631Y438204D01*
G03X114659Y441176I-1486J1486D01*
G01X110722Y437239D01*
G03X110235Y435029I1486J-1486D01*
G01X110279Y434909D01*
X109782Y434412D01*
X108506D01*
X107749Y435169D01*
G03X107589Y435313I-1484J-1488D01*
G02X107558Y435907I252J311D01*
G01X107749Y436097D01*
G03X108364Y437591I-1486J1485D01*
G03X109608Y441312I-93J2099D01*
G01X109600Y441318D01*
X107849Y443069D01*
G03X106680Y443660I-1485J-1486D01*
G01X106510Y443686D01*
Y444524D01*
X107128Y445142D01*
X107722D01*
X110722Y442142D01*
G03X113694Y445114I1486J1486D01*
G01X110501Y448306D01*
X111440Y449245D01*
X113566D01*
X114276Y448535D01*
X114221Y448410D01*
G03X117631Y446079I1924J-845D01*
G01X118998Y447446D01*
X119030Y447461D01*
G03X120160Y448805I-896J1901D01*
G01X120174Y448856D01*
X120337Y449019D01*
X121536D01*
G02X121819Y448336I0J-400D01*
G01X118597Y445114D01*
G03X121569Y442142I1486J-1486D01*
G01X125506Y446079D01*
G03X125823Y448644I-1486J1486D01*
G01X125743Y448778D01*
X126270Y449305D01*
X128034D01*
X129348Y447991D01*
X126471Y445114D01*
G03X129443Y442142I1486J-1486D01*
G01X129962Y442661D01*
X130118Y442504D01*
X130130Y442486D01*
G03X130212Y442368I1766J1140D01*
G01X130252Y442315D01*
Y441017D01*
G37*
G36*
G01X106785Y461827D02*
G03X109757Y464799I1486J1486D01*
G01X108724Y465831D01*
Y465853D01*
X107935Y466643D01*
G03X107752Y466805I-1482J-1490D01*
G01X107743Y466813D01*
X105820Y468736D01*
G03X104140Y469343I-1486J-1486D01*
G02X103927Y469494I-19J199D01*
G03X101110Y469774I-1458J-360D01*
G01X101095Y469742D01*
X101040Y469687D01*
Y469596D01*
X101031Y469568D01*
G03Y468700I1438J-434D01*
G01X101040Y468672D01*
Y467067D01*
X100557Y466584D01*
X99423D01*
X98039Y465200D01*
X97387D01*
X97347Y465219D01*
G03X96684Y465403I-886J-1906D01*
G01X96613Y465411D01*
X95964Y466060D01*
Y468179D01*
X96009Y468234D01*
G03X94985Y470677I-1165J948D01*
G02X94622Y471093I37J399D01*
G03X94009Y472673I-2099J94D01*
G01X91511Y475170D01*
X90350D01*
G03X88521Y474105I-1J-2102D01*
G01X88508Y474081D01*
X88226Y473798D01*
X87650Y474374D01*
Y475834D01*
X87743Y475893D01*
G03X88426Y476965I-806J1267D01*
G03X90240Y477764I160J2096D01*
G02X90869I314J-247D01*
G03X94177I1654J1297D01*
G02X94806I314J-247D01*
G03X95151Y477416I1655J1296D01*
G02X95185Y476821I-249J-313D01*
G01X94974Y476610D01*
G03X97946Y473638I1486J-1486D01*
G01X99405Y475097D01*
X99441Y475112D01*
G03X100213Y475671I-814J1937D01*
G02X100811Y475679I303J-262D01*
G03X100878Y475608I1561J1406D01*
G01X102848Y473638D01*
G03X105820Y476610I1486J1486D01*
G01X105609Y476821D01*
G02X105643Y477416I283J282D01*
G03X105988Y477764I-1310J1644D01*
G02X106617I314J-247D01*
G03X109925I1654J1297D01*
G02X110554I314J-247D01*
G03X112078Y476963I1654J1297D01*
G03X112689Y475608I2097J130D01*
G01X112900Y475397D01*
G02X112866Y474801I-283J-283D01*
G03X112689Y471671I1309J-1644D01*
G01X114659Y469701D01*
G03X117799Y469891I1486J1486D01*
G02X118429I315J-247D01*
G03X118662Y469639I1654J1296D01*
G01X118665Y469636D01*
X119081Y469220D01*
X118597Y468736D01*
G03X121569Y465764I1486J-1486D01*
G01X123539Y467734D01*
G03X124150Y469090I-1486J1485D01*
G03X125674Y469890I-129J2098D01*
G02X126303I314J-247D01*
G03X129443Y469701I1654J1297D01*
G01X133380Y473638D01*
G03X133548Y473827I-1484J1488D01*
G02X134177I314J-247D01*
G03X137317Y473638I1654J1297D01*
G01X139287Y475608D01*
G03X139898Y476963I-1486J1485D01*
G03X141422Y477764I-130J2098D01*
G02X142051I314J-247D01*
G03X145359I1654J1297D01*
G02X145988I314J-247D01*
G03X146333Y477416I1655J1296D01*
G02X146367Y476821I-249J-313D01*
G01X146156Y476610D01*
G03X145545Y475254I1486J-1485D01*
G03X144189Y474643I129J-2097D01*
G01X142219Y472673D01*
G03X145191Y469701I1486J-1486D01*
G01X147161Y471671D01*
G03X147772Y473027I-1486J1485D01*
G03X149128Y473638I-129J2097D01*
G01X149339Y473849D01*
G02X149935Y473815I283J-283D01*
G03X153065Y473638I1644J1309D01*
G01X155035Y475608D01*
G03X155646Y476963I-1486J1485D01*
G03X155924Y476999I-130J2098D01*
G02X156402Y476607I78J-392D01*
G01Y476002D01*
X156445Y475959D01*
Y474986D01*
X156353Y474927D01*
G03X156000Y474643I1133J-1770D01*
G01X154030Y472673D01*
G03X153415Y471159I1486J-1486D01*
G01X153416Y471075D01*
X152651Y470310D01*
X150599D01*
X150543Y470358D01*
G03X148583I-980J-1138D01*
G01X148527Y470310D01*
X148500D01*
X147540Y469350D01*
X147467Y469344D01*
G03X146156Y468736I175J-2094D01*
G01X143365Y465945D01*
X137087D01*
X136556Y465414D01*
X135831D01*
G03X133795Y462792I0J-2101D01*
G01X133823Y462681D01*
X133616Y462474D01*
Y459695D01*
X132349Y458428D01*
X131996D01*
X131566Y458858D01*
G03X128594Y455886I-1486J-1486D01*
G01X129200Y455280D01*
Y455000D01*
X128500Y454300D01*
X128086D01*
X127044Y455342D01*
X125897D01*
G03X124669Y451535I0J-2102D01*
G02X124718Y450927I-234J-325D01*
G01X124636Y450845D01*
X122571D01*
G02X122173Y451286I0J400D01*
G03X122184Y451502I-2090J215D01*
G01Y452427D01*
X119866Y454746D01*
X119860Y454754D01*
G03X116752Y454903I-1622J-1337D01*
G01X115255Y453406D01*
X115225Y453391D01*
G03X114491Y452799I919J-1890D01*
G02X113862I-314J247D01*
G03X113694Y452988I-1652J-1299D01*
G01X111724Y454958D01*
G03X108752I-1486J-1486D01*
G01X108525Y454731D01*
G02X107925Y454769I-283J282D01*
G03X107749Y454969I-1662J-1286D01*
G01X107088Y455630D01*
G02X107114Y456220I283J283D01*
G03X105641Y458784I-965J1151D01*
G01X105608Y458772D01*
X103422D01*
X103337Y458687D01*
X102495Y459529D01*
X102487Y459600D01*
G03X100621Y461466I-2090J-224D01*
G01X100550Y461474D01*
X100107Y461917D01*
X100091Y461959D01*
G03X99793Y462451I-1409J-517D01*
G02X99806Y463003I296J269D01*
G01X100585Y463782D01*
X101719D01*
X103275Y465338D01*
X106785Y461827D01*
G37*
G36*
G01X125718Y472464D02*
X121360Y476822D01*
G02X121393Y477418I283J283D01*
G03X121737Y477764I-1308J1645D01*
G02X122366I315J-247D01*
G03X125674I1654J1297D01*
G02X126303I314J-247D01*
G03X129611I1654J1297D01*
G02X130240I315J-247D01*
G03X130597Y477407I1654J1297D01*
G02Y476777I-247J-315D01*
G03X130408Y476610I1294J-1655D01*
G01X126471Y472673D01*
G03X126314Y472497I1487J-1485D01*
G02X125718Y472464I-313J249D01*
G37*
G36*
G01X78701Y791458D02*
Y881770D01*
X198701D01*
Y854526D01*
X190393D01*
Y871534D01*
X149143D01*
Y873516D01*
G03X140543I-4300J933D01*
G01Y871534D01*
X95237D01*
Y801694D01*
X140543D01*
Y799713D01*
G03X149143I4300J-934D01*
G01Y801694D01*
X190393D01*
Y820276D01*
X198701D01*
Y791458D01*
X78701D01*
G37*
G36*
G01X87500Y888200D02*
X82000Y893700D01*
Y920400D01*
X83427Y921827D01*
X95583D01*
G02X95832Y921114I0J-400D01*
G03X97169Y888932I12436J-15602D01*
G02X96946Y888200I-223J-332D01*
G01X87500D01*
G37*
G36*
G01X119367Y888932D02*
G03X120704Y921114I-11099J16580D01*
G02X120953Y921827I249J313D01*
G01X142827D01*
G02X143076Y921114I0J-400D01*
G03X144413Y888932I12436J-15602D01*
G02X144190Y888200I-223J-332D01*
G01X119590D01*
G02X119367Y888932I0J400D01*
G37*
G36*
G01X211380Y81842D02*
X211869Y82331D01*
X213046D01*
Y82300D01*
X218338D01*
Y69982D01*
X218415D01*
Y65874D01*
X213900Y61359D01*
Y49800D01*
X212200Y48100D01*
X180657D01*
X179257Y49500D01*
Y57543D01*
X174218Y62582D01*
Y108600D01*
X175018Y109400D01*
X195120D01*
X196120Y108400D01*
Y92700D01*
X194800Y91380D01*
Y80600D01*
X196255Y79145D01*
X199922D01*
X199956Y79132D01*
G03X200515Y79032I557J1501D01*
G01X202115D01*
G03X202674Y79132I2J1601D01*
G01X202708Y79145D01*
X203761D01*
X203776Y79143D01*
G03X204011Y79126I233J1584D01*
G01X205611D01*
G03X205846Y79143I2J1601D01*
G01X205861Y79145D01*
X207682D01*
X207696Y79143D01*
G03X207912Y79128I219J1587D01*
G01X209312D01*
G03X209528Y79143I-3J1602D01*
G01X209542Y79145D01*
X210609D01*
X211380Y79916D01*
Y81842D01*
G37*
G36*
G01X207900Y125100D02*
X189500D01*
X188900Y125700D01*
Y134500D01*
X189200Y134800D01*
X197900D01*
X200800Y131900D01*
X208000D01*
X208300Y131600D01*
Y125500D01*
X207900Y125100D01*
G37*
G36*
G01X186700Y126800D02*
X171550D01*
X170950Y127400D01*
Y134950D01*
X172000Y136000D01*
X187000D01*
X187400Y135600D01*
Y127500D01*
X186700Y126800D01*
G37*
G36*
G01X229500Y130900D02*
X227300Y133100D01*
X225939D01*
X225925Y133102D01*
G03X225702Y133118I-226J-1586D01*
G01X224302D01*
G03X224079Y133102I3J-1602D01*
G01X224065Y133100D01*
X221969D01*
X221965D01*
G03X221900Y133102I-82J-1599D01*
G01X220300D01*
G03X220235Y133100I17J-1601D01*
G01X220231D01*
X218253D01*
X218228Y133107D01*
G03X217813Y133162I-416J-1547D01*
G01X216413D01*
G03X215998Y133107I1J-1602D01*
G01X215973Y133100D01*
X209300D01*
X209200Y133200D01*
X202000D01*
X201600Y133600D01*
Y140100D01*
X202000Y140500D01*
X209300D01*
X212500Y143700D01*
Y147700D01*
X213000Y148200D01*
X221700D01*
X222300Y147600D01*
Y142300D01*
X223500Y141100D01*
X238000D01*
X239000Y140100D01*
Y132200D01*
X237700Y130900D01*
X229500D01*
G37*
G36*
G01X171800Y138100D02*
X171300Y138600D01*
Y144800D01*
X174900Y148400D01*
X179300D01*
X181400Y150500D01*
Y154000D01*
X179687Y155713D01*
X179683Y155718D01*
G03X179603Y155803I-1278J-1123D01*
G01X177577Y157830D01*
X177570D01*
X177400Y158000D01*
X172900D01*
X172800Y158100D01*
Y160200D01*
X176694D01*
X176697Y160197D01*
X178193D01*
X178895Y159495D01*
X178900D01*
X179095Y159300D01*
X190500D01*
X191500Y158300D01*
Y151800D01*
X193900Y149400D01*
X196500D01*
X196950Y148950D01*
Y139050D01*
X196000Y138100D01*
X171800D01*
G37*
G36*
G01X180300Y160500D02*
X180100Y160700D01*
Y165900D01*
X180300Y166100D01*
X186800D01*
X187600Y166900D01*
Y176400D01*
X188700Y177500D01*
X197200D01*
X197600Y177100D01*
Y169900D01*
X197100Y169400D01*
X193400D01*
X192700Y168700D01*
Y162000D01*
X191200Y160500D01*
X180300D01*
G37*
G36*
G01X172700Y149900D02*
X172200Y150400D01*
Y154100D01*
X172104Y154196D01*
Y154208D01*
X172092D01*
X171900Y154400D01*
X163900D01*
X163460Y154840D01*
Y161560D01*
X163886Y161986D01*
X166198D01*
Y162000D01*
X168500D01*
Y161986D01*
X170414D01*
X171100Y161300D01*
Y156400D01*
X171300Y156200D01*
X177500D01*
X179900Y153800D01*
Y151300D01*
X178500Y149900D01*
X172700D01*
G37*
G36*
G01X210900Y160700D02*
X209200Y162400D01*
X194200D01*
X194000Y162600D01*
Y168000D01*
X194198Y168198D01*
X197598D01*
X197599Y168200D01*
X198300D01*
X199348Y169248D01*
X201502D01*
Y178152D01*
X200000D01*
Y180700D01*
X201700Y182400D01*
X206400D01*
X208950Y179850D01*
Y174700D01*
X209850Y173800D01*
X213500D01*
X213900Y173400D01*
Y169300D01*
X215200Y168000D01*
X221400D01*
X221900Y167500D01*
Y161400D01*
X221200Y160700D01*
X210900D01*
G37*
G36*
G01X180477Y233980D02*
X180407Y233973D01*
G03X178566Y232680I234J-2290D01*
G01X178551Y232649D01*
X177103Y231201D01*
X174633D01*
X173589Y232245D01*
Y233689D01*
X175000Y235100D01*
X175500D01*
X176182Y235782D01*
Y235800D01*
X176300Y235918D01*
Y243236D01*
X176732Y243667D01*
X177700Y244635D01*
Y245318D01*
X177706Y245342D01*
G03X177752Y245722I-1556J381D01*
G01Y247122D01*
G03X177750Y247191I-1602J-12D01*
G01Y247196D01*
Y247400D01*
X183856D01*
X187033Y250577D01*
X189794D01*
X190386Y249986D01*
Y249263D01*
X190383Y249246D01*
G03X190362Y248983I1580J-259D01*
G01Y247383D01*
G03X190383Y247120I1601J-4D01*
G01X190386Y247103D01*
Y245814D01*
X190379Y245787D01*
G03X190320Y245356I1542J-431D01*
G01Y243756D01*
G03X190379Y243325I1601J0D01*
G01X190386Y243298D01*
Y242063D01*
X190383Y242046D01*
G03X190362Y241783I1580J-259D01*
G01Y240183D01*
G03X190383Y239920I1601J-4D01*
G01X190386Y239903D01*
Y238463D01*
X190383Y238446D01*
G03X190362Y238183I1580J-259D01*
G01Y236583D01*
G03X190383Y236320I1601J-4D01*
G01X190386Y236303D01*
Y235395D01*
X189782Y234791D01*
X184715D01*
X184703Y234803D01*
X181300D01*
X180477Y233980D01*
G37*
G36*
G01X211955Y378566D02*
X211226Y379295D01*
Y383366D01*
X212090Y384230D01*
X225283D01*
X227262Y386210D01*
X227272D01*
Y386220D01*
X228602Y387549D01*
X233118D01*
X234118Y386549D01*
Y385390D01*
X234179Y385329D01*
Y379413D01*
X233332Y378566D01*
X211955D01*
G37*
G36*
G01X215452Y400438D02*
X215451Y400440D01*
X210591D01*
X206896Y404134D01*
X206844D01*
X206778Y404200D01*
X192522D01*
X190502Y402180D01*
X182510D01*
X182509Y402178D01*
X177635D01*
X177513Y402300D01*
Y404449D01*
X177818Y404754D01*
X182734D01*
X182785Y404703D01*
X183793D01*
X183833Y404684D01*
G03X184515Y404532I681J1449D01*
G01X186115D01*
G03X186797Y404684I1J1601D01*
G01X186837Y404703D01*
X187359D01*
X187378Y404722D01*
X187722D01*
X192400Y409400D01*
Y410201D01*
X192684Y410485D01*
X198217D01*
X199388Y409314D01*
X202676D01*
X204049Y407941D01*
X204100D01*
X204241Y407800D01*
X207335D01*
X209626Y405509D01*
X214058D01*
X215270Y404297D01*
X218110D01*
X218407Y404000D01*
Y403793D01*
X218406Y403792D01*
Y400568D01*
X218276Y400438D01*
X215452D01*
G37*
G36*
G01X184100Y405900D02*
X184000Y406000D01*
Y407900D01*
X184200Y408100D01*
X186900D01*
X188100Y409300D01*
Y414300D01*
X188400Y414600D01*
X191500D01*
X192000Y415100D01*
Y422100D01*
X193200Y423300D01*
X196800D01*
X198200Y424700D01*
X203500D01*
X203900Y424300D01*
Y419000D01*
X204400Y418500D01*
X205566D01*
X205590Y418494D01*
G03X205988Y418444I397J1551D01*
G01X207588D01*
G03X207745Y418451I7J1601D01*
G01X207839Y418461D01*
X208000Y418300D01*
Y413329D01*
X207979Y413287D01*
G03Y411243I2063J-1022D01*
G01X208000Y411201D01*
Y409400D01*
X207700Y409100D01*
X204600D01*
X202900Y410800D01*
X200100D01*
X198800Y412100D01*
X191700D01*
X190600Y411000D01*
Y409300D01*
X187200Y405900D01*
X184100D01*
G37*
G36*
G01X204670Y389770D02*
X205007Y389432D01*
X209432D01*
X212644Y392644D01*
X225644D01*
X226244Y392044D01*
Y387100D01*
X224948Y385804D01*
X211652D01*
X209500Y383652D01*
Y380200D01*
X207797Y378497D01*
X168500D01*
X167900Y379097D01*
Y381542D01*
X168500Y382142D01*
X176428D01*
X182463Y388177D01*
X186462D01*
X187185Y388900D01*
X198600D01*
X198910Y389210D01*
Y389590D01*
X199090Y389770D01*
X199543D01*
X199552Y389769D01*
G03X199698Y389762I150J1595D01*
G01X201298D01*
G03X201444Y389769I-4J1602D01*
G01X201453Y389770D01*
X204670D01*
G37*
G36*
G01X209800Y416900D02*
X209400Y417300D01*
Y418800D01*
X208500Y419700D01*
X208299D01*
X208298Y419702D01*
X205798D01*
X205500Y420000D01*
Y425100D01*
X204400Y426200D01*
X197400D01*
X196500Y425300D01*
X193100D01*
X192959Y425441D01*
X192945Y425469D01*
G03X192831Y425671I-2059J-1029D01*
G01X192800Y425720D01*
Y429600D01*
X193200Y430000D01*
X196200D01*
X198300Y432100D01*
X201304D01*
X201308D01*
G03X201492I92J2300D01*
G01X201496D01*
X207100D01*
X208660Y430540D01*
X208675Y430507D01*
G03X209823Y429359I2097J949D01*
G01X209856Y429344D01*
X210000Y429200D01*
Y425900D01*
X213200Y422700D01*
Y417400D01*
X212700Y416900D01*
X209800D01*
G37*
G36*
G01X217271Y520374D02*
X216740Y520905D01*
X216752Y521003D01*
G03X216764Y521203I-1589J196D01*
G01Y522603D01*
G03X216677Y523125I-1601J1D01*
G01X216666Y523157D01*
Y530745D01*
X216629Y530782D01*
Y535147D01*
X223965Y542483D01*
X246215D01*
X247115Y541583D01*
Y532866D01*
X244549Y530300D01*
X241400D01*
X240682Y529582D01*
Y524704D01*
X240484Y524506D01*
X225832D01*
X224777Y525561D01*
X220321D01*
X219454Y524694D01*
Y520875D01*
X218953Y520374D01*
X217271D01*
G37*
G36*
G01X345133Y814504D02*
X345258Y814448D01*
G03X343095Y816611I1724J3887D01*
G01X343151Y816486D01*
X341382Y814718D01*
Y807134D01*
X317892D01*
Y814179D01*
X318042Y814217D01*
G03X314983Y814582I-1060J4118D01*
G01X315088Y814526D01*
Y807134D01*
X308328D01*
Y814299D01*
X308459Y814348D01*
G03X305400Y814388I-1478J3987D01*
G01X305526Y814338D01*
Y807134D01*
X297060D01*
Y814084D01*
G03X294188Y815130I-78J4251D01*
G01X294256Y815070D01*
Y807134D01*
X287136D01*
Y814086D01*
G03X284261Y815067I-155J4249D01*
G01X284334Y815007D01*
Y807134D01*
X280172D01*
Y815522D01*
X280219Y815578D01*
G03X279276Y821915I-3237J2757D01*
G01X279184Y821974D01*
Y824696D01*
X279276Y824755D01*
G03Y831915I-2294J3580D01*
G01X279184Y831974D01*
Y843627D01*
X279236Y843684D01*
G03X279656Y844765I-1181J1081D01*
G01Y846365D01*
G03X278054Y847966I-1601J0D01*
G01X276454D01*
G03X274853Y846405I0J-1602D01*
G01X274851Y846325D01*
X274780Y846255D01*
Y831974D01*
X274688Y831915D01*
G03Y824755I2294J-3580D01*
G01X274780Y824696D01*
Y821974D01*
X274688Y821915D01*
G03X275632Y814303I2294J-3580D01*
G01X275768Y814257D01*
Y807134D01*
X234166D01*
X227200Y814100D01*
Y840600D01*
X204900Y862900D01*
Y884800D01*
X201500Y888200D01*
X166834D01*
G02X166611Y888932I0J400D01*
G03X167948Y921114I-11099J16580D01*
G02X168197Y921827I249J313D01*
G01X753393D01*
X755762Y919458D01*
Y833568D01*
X753175Y830981D01*
X746950D01*
X739988Y837943D01*
Y862512D01*
X736108Y866392D01*
X732192D01*
X732191Y866394D01*
X672850D01*
X644423Y837967D01*
Y827742D01*
X644392Y827693D01*
G03Y825245I1950J-1224D01*
G01X644423Y825196D01*
Y759082D01*
X661272Y742233D01*
X661277Y742157D01*
G03X663443Y739991I2298J132D01*
G01X663519Y739986D01*
X664559Y738946D01*
X665870D01*
X665925Y738836D01*
G03X670039I2057J1034D01*
G01X670094Y738946D01*
X689551D01*
X695414Y744809D01*
Y757400D01*
X695801Y757787D01*
Y764799D01*
X696065Y765063D01*
X720168D01*
X733375Y751856D01*
Y743825D01*
X756700Y720500D01*
Y661000D01*
X760700Y657000D01*
X769300D01*
X769600Y656700D01*
Y647500D01*
X769014Y646914D01*
X283757D01*
X186987Y550144D01*
X176444D01*
X172772Y553816D01*
Y721911D01*
X216434Y765573D01*
X220449D01*
G02X220846Y765122I0J-400D01*
G03X225412I2283J-292D01*
G02X225809Y765573I397J51D01*
G01X234932D01*
X238859Y769500D01*
X239000Y769376D01*
G03X243276Y771791I1715J1957D01*
G01X243258Y771894D01*
X244466Y773101D01*
Y783266D01*
X244731Y783532D01*
X328096D01*
X329255Y784690D01*
X331442D01*
X331501Y784597D01*
G03X336241I2370J1495D01*
G01X336300Y784690D01*
X351661D01*
X352347Y785377D01*
X362446D01*
X366598Y789529D01*
Y803984D01*
X363448Y807134D01*
X344186D01*
Y813556D01*
X345133Y814504D01*
G37*
G36*
G01X237483Y82300D02*
X238813Y80971D01*
X238822Y80905D01*
G03X240563Y78992I2279J325D01*
G01X240716Y78955D01*
Y73416D01*
X243032Y71100D01*
X247100D01*
X247766Y70434D01*
Y67996D01*
G03X247773Y67841I1601J-5D01*
G01X247774Y67831D01*
Y67126D01*
X248600Y66300D01*
X284300D01*
X285515Y65085D01*
Y58933D01*
X284015Y57433D01*
X279816D01*
X279742Y57358D01*
X228942D01*
X228412Y57888D01*
Y62488D01*
X228500Y62576D01*
X230971D01*
X233800Y65405D01*
Y69982D01*
X233842D01*
Y82208D01*
X233934Y82300D01*
X237483D01*
G37*
G36*
G01X377300Y30400D02*
X306000D01*
X296251Y40149D01*
X272300D01*
X269874Y42575D01*
Y52726D01*
X271286Y54137D01*
X377063D01*
X378300Y52900D01*
Y31400D01*
X377300Y30400D01*
G37*
G36*
G01X230644Y67168D02*
X230545Y67183D01*
G03X230313Y67200I-232J-1575D01*
G01X228913D01*
G03X228588Y67166I3J-1602D01*
G01X228568Y67162D01*
X226629D01*
X226590Y67180D01*
G03X225931Y67322I-659J-1460D01*
G01X224531D01*
G03X223872Y67180I0J-1602D01*
G01X223833Y67162D01*
X220812D01*
X220137Y67837D01*
Y96818D01*
X220143Y96842D01*
G03X220190Y97163I-1553J391D01*
G01X220193Y97240D01*
X222397Y99444D01*
X231409D01*
X232288Y98564D01*
Y68812D01*
X230644Y67168D01*
G37*
G36*
G01X242002Y131100D02*
Y139752D01*
X242000D01*
X241898Y139998D01*
X242200Y140300D01*
X252600D01*
X253200Y139700D01*
Y132000D01*
X252300Y131100D01*
X242002D01*
G37*
G36*
G01X253300Y377773D02*
X251500Y379573D01*
Y388400D01*
X250400Y389500D01*
X248400D01*
X248300Y389600D01*
Y391879D01*
G02X248703Y392279I400J0D01*
G03X248715Y392278I139J1590D01*
G01X250315D01*
G03X250893Y392387I-3J1601D01*
G01X250928Y392400D01*
X251572D01*
X251632Y392321D01*
G03X254731Y396289I2068J1579D01*
G01X254696Y396304D01*
X253700Y397300D01*
X253000D01*
X252200Y398100D01*
Y400500D01*
X252400Y400700D01*
X256800D01*
X256900Y400800D01*
X259400D01*
X260200Y400000D01*
X262300D01*
X263700Y401400D01*
Y403300D01*
X262300Y404700D01*
X259300D01*
X258500Y405500D01*
X257592D01*
X257584Y405501D01*
G03X257216I-184J-2295D01*
G01X257208Y405500D01*
X256800D01*
X256700Y405600D01*
X252500D01*
X251600Y406500D01*
Y422917D01*
X253100Y424417D01*
X294600D01*
X298717Y420300D01*
X324400D01*
X325400Y419300D01*
Y405883D01*
X326700Y404583D01*
X348328D01*
X357311Y395600D01*
X406150D01*
X407926Y397377D01*
Y430458D01*
X405584Y432800D01*
X388180D01*
X388163Y432803D01*
G03X387900Y432824I-259J-1580D01*
G01X386300D01*
G03X386037Y432803I-4J-1601D01*
G01X386020Y432800D01*
X384182D01*
X384165Y432803D01*
G03X383902Y432824I-259J-1580D01*
G01X382302D01*
G03X382039Y432803I-4J-1601D01*
G01X382022Y432800D01*
X380264D01*
X380247Y432803D01*
G03X379984Y432824I-259J-1580D01*
G01X378384D01*
G03X378121Y432803I-4J-1601D01*
G01X378104Y432800D01*
X376544D01*
X376527Y432803D01*
G03X376264Y432824I-259J-1580D01*
G01X374664D01*
G03X374401Y432803I-4J-1601D01*
G01X374384Y432800D01*
X372267D01*
X372250Y432803D01*
G03X371987Y432824I-259J-1580D01*
G01X370387D01*
G03X370124Y432803I-4J-1601D01*
G01X370107Y432800D01*
X368512D01*
X368495Y432803D01*
G03X368232Y432824I-259J-1580D01*
G01X366632D01*
G03X366369Y432803I-4J-1601D01*
G01X366352Y432800D01*
X365048D01*
X365031Y432803D01*
G03X364768Y432824I-259J-1580D01*
G01X363168D01*
G03X362905Y432803I-4J-1601D01*
G01X362888Y432800D01*
X361495D01*
X361478Y432803D01*
G03X361215Y432824I-259J-1580D01*
G01X359615D01*
G03X359352Y432803I-4J-1601D01*
G01X359335Y432800D01*
X357794D01*
X357777Y432803D01*
G03X357514Y432824I-259J-1580D01*
G01X355914D01*
G03X355651Y432803I-4J-1601D01*
G01X355634Y432800D01*
X353894D01*
X353877Y432803D01*
G03X353614Y432824I-259J-1580D01*
G01X352014D01*
G03X351751Y432803I-4J-1601D01*
G01X351734Y432800D01*
X349994D01*
X349977Y432803D01*
G03X349714Y432824I-259J-1580D01*
G01X348114D01*
G03X347851Y432803I-4J-1601D01*
G01X347834Y432800D01*
X346094D01*
X346077Y432803D01*
G03X345814Y432824I-259J-1580D01*
G01X344214D01*
G03X343951Y432803I-4J-1601D01*
G01X343934Y432800D01*
X342424D01*
X342407Y432803D01*
G03X342144Y432824I-259J-1580D01*
G01X340544D01*
G03X340281Y432803I-4J-1601D01*
G01X340264Y432800D01*
X338692D01*
X338675Y432803D01*
G03X338412Y432824I-259J-1580D01*
G01X336812D01*
G03X336549Y432803I-4J-1601D01*
G01X336532Y432800D01*
X324700D01*
X314900Y442600D01*
X288400D01*
X287300Y443700D01*
Y468600D01*
X288400Y469700D01*
X293200D01*
X295100Y467800D01*
X295800D01*
X296000Y467600D01*
Y464600D01*
X296600Y464000D01*
Y459800D01*
X297500Y458900D01*
Y452600D01*
X298300Y451800D01*
X309400D01*
X310100Y452500D01*
Y461800D01*
X310733Y462433D01*
X335515D01*
X338395Y465313D01*
X379713D01*
X384585Y460441D01*
X386485D01*
X386511Y460433D01*
G03X387775I632J2214D01*
G01X387801Y460441D01*
X388497D01*
X392004Y463948D01*
Y468066D01*
X391976Y468094D01*
Y470372D01*
X381515Y480833D01*
X351267D01*
X350278Y481822D01*
Y497988D01*
X346983Y501283D01*
X269717D01*
X268100Y502900D01*
Y523000D01*
X266700Y524400D01*
X249800D01*
X248500Y523100D01*
X244069D01*
X244065D01*
G03X244000Y523102I-82J-1599D01*
G01X242400D01*
G03X242335Y523100I17J-1601D01*
G01X242331D01*
X242200D01*
X241900Y523400D01*
Y528400D01*
X242500Y529000D01*
X245300D01*
X249100Y532800D01*
Y541500D01*
X256340Y548740D01*
Y569240D01*
X278721Y591622D01*
G02X279326Y591575I282J-283D01*
G03X282544Y594793I1857J1361D01*
G02X282497Y595398I236J323D01*
G01X284531Y597432D01*
Y597638D01*
X634266D01*
X639482Y592422D01*
Y584400D01*
X432855Y377773D01*
X253300D01*
G37*
G36*
G01X273350Y425650D02*
X256500D01*
X255525Y426625D01*
Y440025D01*
X256450Y440950D01*
X266750D01*
X270200Y437500D01*
X272600D01*
X274000Y436100D01*
Y426300D01*
X273350Y425650D01*
G37*
G36*
G01X303700Y480400D02*
X301767Y482333D01*
X288000D01*
X286567Y480900D01*
X274433D01*
X271700Y483633D01*
Y487700D01*
X270800Y488600D01*
X268200D01*
X267866Y488266D01*
X261336D01*
X261316Y488270D01*
G03X261000Y488302I-319J-1570D01*
G01X259400D01*
G03X259084Y488270I3J-1602D01*
G01X259064Y488266D01*
X257836D01*
X257816Y488270D01*
G03X257500Y488302I-319J-1570D01*
G01X255900D01*
G03X255584Y488270I3J-1602D01*
G01X255564Y488266D01*
X254500D01*
X253566Y489200D01*
X251300D01*
X250715Y489785D01*
Y489800D01*
X250400Y490115D01*
Y498400D01*
X251000Y499000D01*
X346500D01*
X348615Y496885D01*
Y481215D01*
X347800Y480400D01*
X303700D01*
G37*
G36*
G01X251800Y481900D02*
X250750Y482950D01*
Y487150D01*
X251500Y487900D01*
X252900D01*
X253700Y487100D01*
X253967D01*
X254002Y487064D01*
X268364D01*
X268399Y487100D01*
X268600D01*
X268800Y487300D01*
X270000D01*
X270498Y486802D01*
Y483798D01*
X268600Y481900D01*
X251800D01*
G37*
G36*
G01X226415Y501133D02*
X224415Y503133D01*
Y507733D01*
X225815Y509133D01*
X232215D01*
X232224Y509124D01*
X234409D01*
X236833Y506700D01*
X265600D01*
X266000Y506300D01*
Y501800D01*
X265333Y501133D01*
X229060D01*
X229037Y501139D01*
G03X227963I-537J-2239D01*
G01X227940Y501133D01*
X226415D01*
G37*
G36*
G01X237000Y508398D02*
X234824Y510574D01*
X224200D01*
X223076Y511698D01*
Y517624D01*
X225385Y519933D01*
Y520679D01*
X225395Y520710D01*
G03X225478Y521219I-1519J509D01*
G01Y521688D01*
X226612Y522822D01*
X239704D01*
X240626Y521900D01*
X241701D01*
X241702Y521898D01*
X248998D01*
X248999Y521900D01*
X249214D01*
X250056Y522742D01*
X264127D01*
X265247Y521622D01*
Y509038D01*
X264607Y508398D01*
X237000D01*
G37*
G36*
G01X402454Y396846D02*
X358689D01*
X349585Y405950D01*
X329500D01*
X327800Y407650D01*
Y430086D01*
X329300Y431586D01*
X402186D01*
X403905Y429868D01*
Y398298D01*
X402454Y396846D01*
G37*
G36*
G01X385106Y461642D02*
X380224Y466524D01*
X366483D01*
X366468Y466526D01*
G03X366227Y466544I-239J-1583D01*
G01X364627D01*
G03X364386Y466526I-2J-1601D01*
G01X364371Y466524D01*
X362698D01*
X362683Y466526D01*
G03X362442Y466544I-239J-1583D01*
G01X360842D01*
G03X360601Y466526I-2J-1601D01*
G01X360586Y466524D01*
X359068D01*
X359053Y466526D01*
G03X358812Y466544I-239J-1583D01*
G01X357212D01*
G03X356971Y466526I-2J-1601D01*
G01X356956Y466524D01*
X354954D01*
X354939Y466526D01*
G03X354698Y466544I-239J-1583D01*
G01X353098D01*
G03X352857Y466526I-2J-1601D01*
G01X352842Y466524D01*
X351057D01*
X351038Y466527D01*
G03X350745Y466554I-293J-1574D01*
G01X349145D01*
G03X348852Y466527I0J-1601D01*
G01X348833Y466524D01*
X346869D01*
X346854Y466526D01*
G03X346613Y466544I-239J-1583D01*
G01X345013D01*
G03X344772Y466526I-2J-1601D01*
G01X344757Y466524D01*
X337700D01*
X336909Y465733D01*
X304215D01*
X303315Y466633D01*
Y469233D01*
X303115Y469433D01*
Y476733D01*
X303141Y476759D01*
Y477841D01*
X304000Y478700D01*
X381800D01*
X390774Y469726D01*
Y467596D01*
X390802Y467568D01*
Y464446D01*
X387999Y461642D01*
X385106D01*
G37*
G36*
G01X300000Y453200D02*
X299715Y453485D01*
Y453500D01*
X299100Y454115D01*
Y459400D01*
X298100Y460400D01*
Y464200D01*
X297400Y464900D01*
Y468348D01*
X296548Y469200D01*
X295400D01*
X293300Y471300D01*
X291200D01*
X289891Y472609D01*
Y478809D01*
X292015Y480933D01*
X300667D01*
X301624Y479976D01*
Y469076D01*
X302114Y468586D01*
Y466135D01*
X302115Y466134D01*
Y466033D01*
X303748Y464400D01*
X307615D01*
X308115Y463900D01*
Y453715D01*
X307600Y453200D01*
X300000D01*
G37*
G36*
G01X318400Y426400D02*
X309900Y434900D01*
X304296D01*
X304292D01*
G03X304108I-92J-2300D01*
G01X304104D01*
X291200D01*
X290900Y435200D01*
Y440400D01*
X291300Y440800D01*
X314900D01*
X322200Y433500D01*
Y427400D01*
X321200Y426400D01*
X318400D01*
G37*
G36*
G01X637900Y509100D02*
X637100Y509900D01*
Y520005D01*
X637101Y520016D01*
G03X637124Y520400I-3178J383D01*
G01Y523525D01*
X637600Y524000D01*
X648300D01*
X648900Y523400D01*
Y510000D01*
X648000Y509100D01*
X637900D01*
G37*
G36*
G01X667796Y511351D02*
X666947Y510501D01*
X666246Y509800D01*
X651900D01*
X651158Y510542D01*
Y511358D01*
X651151Y511365D01*
Y523428D01*
X649150Y525429D01*
X640724D01*
Y534564D01*
X638300D01*
Y537400D01*
X638800Y537900D01*
X641200D01*
X645100Y534000D01*
X647500D01*
X648100Y533400D01*
Y531300D01*
X648800Y530600D01*
X649931D01*
X649935D01*
G03X650000Y530598I82J1599D01*
G01X651400D01*
G03X651465Y530600I-17J1601D01*
G01X651469D01*
X652100D01*
X652498Y530202D01*
Y528800D01*
G03X652502Y528700I1601J14D01*
G01Y528694D01*
Y527998D01*
X654000Y526500D01*
X655563D01*
X656149Y525914D01*
X656164Y525874D01*
G03X658957Y524487I2150J823D01*
G01X658984Y524494D01*
X659212D01*
Y524426D01*
X664656D01*
Y516168D01*
X664733D01*
X664900Y516000D01*
X667796D01*
Y511351D01*
G37*
G36*
G01X719027Y530800D02*
X717300D01*
X715000Y528500D01*
X709300D01*
X708300Y529500D01*
Y536700D01*
X708900Y537300D01*
X710700D01*
X714000Y540600D01*
X722700D01*
X725100Y538200D01*
Y531800D01*
X724100Y530800D01*
X720705D01*
X720671Y530813D01*
G03X719061I-805J-2157D01*
G01X719027Y530800D01*
G37*
G36*
G01X669100Y512000D02*
Y517400D01*
X668900Y517600D01*
X666700D01*
X666200Y518100D01*
Y530200D01*
X669000D01*
X669010Y530210D01*
X669040D01*
Y530240D01*
X669100Y530300D01*
Y540000D01*
X669350Y540250D01*
X675750D01*
X676400Y539600D01*
Y537800D01*
X675300Y536700D01*
Y530300D01*
X675500Y530100D01*
X678000D01*
X678400Y529700D01*
Y518100D01*
X677900Y517600D01*
X675600D01*
X675400Y517400D01*
Y512000D01*
X675133D01*
X675102Y512010D01*
G03X673648I-727J-2184D01*
G01X673617Y512000D01*
X669100D01*
G37*
G36*
G01X701017Y512450D02*
X700996Y512454D01*
G03X700222Y512488I-487J-2250D01*
G01X700125Y512475D01*
X699900Y512700D01*
Y527400D01*
X700398Y527898D01*
X704748D01*
X704749Y527900D01*
X706700D01*
X707400Y527200D01*
X712900D01*
X713900Y526200D01*
Y516300D01*
X710050Y512450D01*
X701017D01*
G37*
G36*
G01X697900Y510100D02*
X694302Y506502D01*
X677446D01*
X676675Y507273D01*
Y509730D01*
Y509734D01*
G03Y509918I-2300J92D01*
G01Y509922D01*
Y510724D01*
X676718D01*
Y516121D01*
X678055D01*
X678067Y516133D01*
X679933D01*
X680000Y516200D01*
Y524426D01*
X685302D01*
Y524948D01*
X689453Y529100D01*
X690491D01*
X694700Y533309D01*
Y536300D01*
X695400Y537000D01*
X703600D01*
X704650Y535950D01*
Y529500D01*
X704250Y529100D01*
X698700D01*
X697900Y528300D01*
Y510100D01*
G37*
%LPC*%
G75*
G36*
G01X194321Y242956D02*
X194363Y242583D01*
Y241783D01*
X193563D01*
Y242583D01*
X193521Y242956D01*
Y243756D01*
X194321D01*
Y242956D01*
G37*
G36*
G01X717305Y28346D02*
X716791Y28322D01*
X716279D01*
X715765Y28346D01*
X715259Y28393D01*
X714746Y28462D01*
X714232Y28558D01*
X713729Y28681D01*
X713244Y28820D01*
X712757Y28984D01*
X712278Y29171D01*
X711807Y29380D01*
X711350Y29608D01*
X710898Y29861D01*
X710457Y30137D01*
X710040Y30427D01*
X709626Y30740D01*
X709237Y31071D01*
X708859Y31414D01*
X708495Y31784D01*
X708148Y32166D01*
X707824Y32566D01*
X707517Y32979D01*
X707231Y33405D01*
X706964Y33841D01*
X706717Y34291D01*
X706486Y34761D01*
X706287Y35237D01*
X706111Y35702D01*
X705945Y36197D01*
X705809Y36702D01*
X705698Y37205D01*
X705612Y37698D01*
X705541Y38207D01*
X705500Y38730D01*
X705482Y39241D01*
X705488Y39754D01*
X705518Y40268D01*
X705571Y40784D01*
X705653Y41293D01*
X705750Y41786D01*
X705875Y42297D01*
X706028Y42792D01*
X706195Y43269D01*
X706386Y43743D01*
X706599Y44217D01*
X706843Y44680D01*
X707095Y45116D01*
X707369Y45547D01*
X707670Y45972D01*
X707983Y46373D01*
X708318Y46768D01*
X708677Y47145D01*
X709043Y47499D01*
X709431Y47839D01*
X709837Y48163D01*
X710247Y48457D01*
X710670Y48741D01*
X711123Y49009D01*
X711575Y49246D01*
X712040Y49471D01*
X712512Y49663D01*
X712992Y49842D01*
X713492Y49996D01*
X713989Y50125D01*
X714485Y50228D01*
X714992Y50316D01*
X715508Y50376D01*
X716023Y50411D01*
X716535Y50423D01*
X717047Y50411D01*
X717562Y50376D01*
X718078Y50316D01*
X718585Y50228D01*
X719081Y50125D01*
X719578Y49996D01*
X720078Y49842D01*
X720558Y49663D01*
X721030Y49471D01*
X721495Y49246D01*
X721947Y49009D01*
X722400Y48741D01*
X722823Y48457D01*
X723233Y48163D01*
X723639Y47839D01*
X724027Y47499D01*
X724393Y47145D01*
X724752Y46768D01*
X725087Y46373D01*
X725400Y45972D01*
X725701Y45547D01*
X725975Y45116D01*
X726227Y44680D01*
X726471Y44217D01*
X726684Y43743D01*
X726875Y43269D01*
X727042Y42792D01*
X727195Y42297D01*
X727320Y41786D01*
X727417Y41293D01*
X727499Y40784D01*
X727552Y40268D01*
X727582Y39754D01*
X727588Y39241D01*
X727570Y38730D01*
X727529Y38207D01*
X727458Y37698D01*
X727372Y37205D01*
X727261Y36702D01*
X727125Y36197D01*
X726959Y35702D01*
X726783Y35237D01*
X726584Y34761D01*
X726353Y34291D01*
X726106Y33841D01*
X725839Y33405D01*
X725553Y32979D01*
X725246Y32566D01*
X724922Y32166D01*
X724575Y31784D01*
X724211Y31414D01*
X723833Y31071D01*
X723444Y30740D01*
X723030Y30427D01*
X722613Y30137D01*
X722172Y29861D01*
X721720Y29608D01*
X721263Y29380D01*
X720792Y29171D01*
X720313Y28984D01*
X719826Y28820D01*
X719341Y28681D01*
X718838Y28558D01*
X718324Y28462D01*
X717811Y28393D01*
X717305Y28346D01*
G37*
G36*
G01X29482Y357816D02*
G03X29840Y357298I382J-119D01*
G02X27502Y355684I-140J-2298D01*
G03X27144Y356202I-382J119D01*
G02X29482Y357816I140J2298D01*
G37*
G36*
G01X57496Y302648D02*
G03X58106Y302324I400J16D01*
G02X57126Y299658I1210J-1958D01*
G03X56451Y299806I-381J-123D01*
G02X57496Y302648I-2904J2681D01*
G37*
G36*
G01X230151Y203538D02*
Y200738D01*
X218667D01*
Y209146D01*
X218567Y209204D01*
G02X217809Y212486I1150J1994D01*
G02X217254Y213698I1046J1212D01*
G01Y215298D01*
G02X218855Y216900I1601J1D01*
G01X220455D01*
G02X221013Y216799I0J-1592D01*
G01X221047Y216786D01*
X222444D01*
X222476Y216798D01*
G02X223002Y216886I524J-1513D01*
G01X224402D01*
G02X224578Y216877I6J-1601D01*
G01X224589Y216876D01*
X224800D01*
Y217881D01*
X224796Y217901D01*
G02X224764Y218217I1570J319D01*
G01Y219617D01*
G02X224796Y219933I1602J-3D01*
G01X224800Y219953D01*
Y222213D01*
X224780Y222255D01*
G02X224516Y223494I2336J1145D01*
G01X224519Y223581D01*
X224300Y223800D01*
Y225900D01*
X225800Y227400D01*
X229300D01*
X233700Y223000D01*
Y217200D01*
X234329Y216571D01*
X234432Y216589D01*
G02X234714Y216614I282J-1576D01*
G01X236114D01*
G02X237716Y215013I1J-1601D01*
G01Y213613D01*
G02X237702Y213403I-1602J1D01*
G01X237700Y213390D01*
Y212900D01*
X236600Y211800D01*
X231200D01*
X230400Y211000D01*
Y206342D01*
X233505D01*
X233565Y206427D01*
G02Y203453I2135J-1487D01*
G01X233505Y203538D01*
X230151D01*
G37*
G36*
G01X226400Y173200D02*
X225100Y171900D01*
X219000D01*
X217200Y173700D01*
Y178200D01*
X216500Y178900D01*
X214600D01*
X213000Y180500D01*
Y182700D01*
X214600Y184300D01*
X218100D01*
X218500Y184700D01*
Y192800D01*
X218700Y193000D01*
X227600D01*
Y185242D01*
X228508Y184334D01*
X232786D01*
X232845Y184428D01*
G02X233574Y180662I2370J-1495D01*
G01X233521Y180700D01*
X230900D01*
X230600Y180400D01*
Y179500D01*
X226400Y175300D01*
Y173200D01*
G37*
G36*
G01X129443Y418519D02*
X127741Y416817D01*
X127738Y416813D01*
G02X124078Y418224I-1558J1411D01*
G01Y419098D01*
X126471Y421491D01*
G02X129443Y418519I1486J-1486D01*
G37*
G36*
G01X137317Y413617D02*
G02X134345Y410645I-1486J-1486D01*
G01X133217Y411773D01*
X133174Y411788D01*
G02X131878Y413084I689J1985D01*
G01X131863Y413127D01*
X130408Y414582D01*
G02X133380Y417554I1486J1486D01*
G01X137317Y413617D01*
G37*
G36*
G01X131413Y463797D02*
X129443Y461827D01*
G02X126471Y464799I-1486J1486D01*
G01X128441Y466769D01*
G02X131413Y463797I1486J-1486D01*
G37*
G36*
G01X111226Y465148D02*
X106170Y470205D01*
Y471187D01*
G02X110092Y472235I2101J0D01*
G01X110106Y472212D01*
X113233Y469085D01*
X113256Y469071D01*
G02X112208Y465148I-1048J-1822D01*
G01X111226D01*
G37*
G36*
G01X204011Y76327D02*
X203211D01*
X202915Y76233D01*
X202115D01*
Y77033D01*
X202915D01*
X203211Y77127D01*
X204011D01*
Y76327D01*
G37*
G36*
G01X188321Y242956D02*
X188363Y242583D01*
Y241783D01*
X187563D01*
Y242583D01*
X187521Y242956D01*
Y243756D01*
X188321D01*
Y242956D01*
G37*
G36*
G01X698592Y761372D02*
X698539Y760999D01*
Y760199D01*
X697739D01*
Y760999D01*
X697792Y761372D01*
Y762172D01*
X698592D01*
Y761372D01*
G37*
G36*
G01X228900Y736600D02*
X227600Y735300D01*
X215700D01*
X214400Y736600D01*
Y743300D01*
X210800Y746900D01*
Y749500D01*
X212300Y751000D01*
X217700D01*
X218300Y751600D01*
Y759600D01*
X218800Y760100D01*
X227400D01*
X227600Y759900D01*
Y758800D01*
X227591Y758791D01*
Y752239D01*
X227896Y751934D01*
X230434D01*
X233007Y754507D01*
X232982Y754614D01*
G02X235096Y752500I2733J619D01*
G01X234989Y752525D01*
X232500Y750036D01*
Y746800D01*
X228900Y743200D01*
Y736600D01*
G37*
G36*
G01X282152Y531090D02*
G03X281881Y531080I-130J-152D01*
G02X281764Y534456I-1622J1634D01*
G03X282035Y534466I130J152D01*
G02X282152Y531090I1622J-1634D01*
G37*
G36*
G01X486172Y530754D02*
X483485D01*
X481102Y533136D01*
X481077Y533150D01*
G02X484202Y536275I1106J2019D01*
G01X484216Y536250D01*
X485309Y535156D01*
X486172D01*
X486204Y535168D01*
G02X486730Y535256I524J-1513D01*
G01X488130D01*
G02X488310Y535246I1J-1601D01*
G03X488720Y535807I45J397D01*
G02X488582Y536459I1463J650D01*
G01Y537859D01*
G02X488710Y538487I1601J1D01*
G03X488301Y539042I-368J157D01*
G02X488138Y539034I-160J1593D01*
G01X486738D01*
G02X486212Y539122I-2J1601D01*
G01X486180Y539134D01*
X483045D01*
X482449Y539729D01*
X482424Y539743D01*
G02X484944Y543579I1107J2019D01*
G01X484998Y543536D01*
X486180D01*
X486212Y543548D01*
G02X486738Y543636I524J-1513D01*
G01X488138D01*
G02X488484Y543599I4J-1601D01*
G03X488681Y543922I43J195D01*
G02X488312Y544945I1232J1023D01*
G01Y546345D01*
G02X488477Y547054I1601J1D01*
G03X488059Y547627I-358J177D01*
G02X487823Y547610I-233J1584D01*
G01X486423D01*
G02X484822Y549211I0J1601D01*
G01Y550611D01*
G02X484866Y550986I1601J2D01*
G01X484872Y551009D01*
Y553421D01*
X484863Y553448D01*
G02X488776Y555643I2210J646D01*
G03X489369Y555644I296J269D01*
G02X492673Y551690I1931J-1744D01*
G03X492606Y551419I106J-170D01*
G02X492824Y550611I-1383J-807D01*
G01Y549211D01*
G02X492376Y548099I-1601J-1D01*
G03X492394Y547527I288J-277D01*
G02X492914Y546345I-1081J-1181D01*
G01Y545376D01*
X493589Y544701D01*
X501368D01*
Y541640D01*
X502060D01*
X502108Y541669D01*
G02X501995Y537804I1192J-1969D01*
G03X501368Y537474I-227J-329D01*
G01Y535777D01*
X494102D01*
Y534194D01*
X493132Y533224D01*
Y532255D01*
G02X492625Y531087I-1602J1D01*
G03X492627Y530502I274J-292D01*
G02X493138Y529328I-1090J-1173D01*
G01Y527928D01*
G02X492712Y526840I-1602J0D01*
G03X492719Y526561I147J-136D01*
G02X489022Y526501I-1819J-1861D01*
G03X489018Y526783I-144J139D01*
G02X488536Y527928I1119J1145D01*
G01Y529328D01*
G02X488723Y530080I1601J1D01*
G03X488322Y530665I-353J188D01*
G02X488130Y530654I-187J1590D01*
G01X486730D01*
G02X486204Y530742I-2J1601D01*
G01X486172Y530754D01*
G37*
G36*
G01X463400Y483100D02*
X461700Y481400D01*
X458900D01*
X454600Y485700D01*
Y491500D01*
X455400Y492300D01*
X456335D01*
X456341D01*
G02X456441Y492304I114J-1597D01*
G01X457804D01*
X458100Y492600D01*
Y496000D01*
X452500Y501600D01*
X452166D01*
X452152Y501598D01*
G02X451923Y501582I-226J1585D01*
G01X450323D01*
G02X450094Y501598I-3J1601D01*
G01X450080Y501600D01*
X449700D01*
X449600Y501500D01*
Y495900D01*
X448500Y494800D01*
X446200D01*
X444500Y496500D01*
Y500200D01*
X443500Y501200D01*
X441500D01*
X439900Y502800D01*
Y505100D01*
X441300Y506500D01*
X444300D01*
X445000Y507200D01*
Y512900D01*
X449300Y517200D01*
X450573D01*
X450588Y517202D01*
G02X451442I427J-2769D01*
G01X451457Y517200D01*
X452300D01*
X453800Y515700D01*
Y514741D01*
X453801Y514731D01*
G02Y514135I-2786J-298D01*
G01X453800Y514125D01*
Y511400D01*
X454200Y511000D01*
X458700D01*
X459800Y512100D01*
Y516200D01*
X461600Y518000D01*
Y520100D01*
X463100Y521600D01*
X464198D01*
X464202D01*
G02X464398I98J-2600D01*
G01X464402D01*
X465600D01*
X466400Y520800D01*
X470800D01*
X472300Y519300D01*
Y513600D01*
X471000Y512300D01*
X465300D01*
X464300Y511300D01*
Y498200D01*
X463100Y497000D01*
Y485300D01*
X463400Y485000D01*
Y483100D01*
G37*
G36*
G01X504391Y477201D02*
G03X503977Y476860I-18J-400D01*
G02X501809Y479499I-2277J340D01*
G03X502223Y479840I18J400D01*
G02X504391Y477201I2277J-340D01*
G37*
G36*
G01X431500Y478683D02*
G03X431820Y479109I-79J392D01*
G02X432517Y481117I2592J225D01*
G03X432531Y481650I-291J274D01*
G02X437037Y483973I1984J1683D01*
G03X437541Y483689I388J99D01*
G02X437398Y478759I759J-2489D01*
G03X436880Y478511I-139J-375D01*
G02X434926Y476783I-2469J823D01*
G03X434606Y476357I79J-392D01*
G02X431500Y478683I-2592J-225D01*
G37*
G36*
G01X411947Y472271D02*
G03X411944Y471681I268J-296D01*
G02X408432Y471698I-1765J-1912D01*
G03X408435Y472288I-268J296D01*
G02X411947Y472271I1765J1912D01*
G37*
G36*
G01X418479Y469152D02*
G03X419069Y469077I329J228D01*
G02X418684Y466023I1506J-1741D01*
G03X418094Y466098I-329J-228D01*
G02X418479Y469152I-1506J1741D01*
G37*
G36*
G01X272179Y384876D02*
G03X271629Y384807I-239J-321D01*
G02X271215Y388102I-1789J1449D01*
G03X271765Y388171I239J321D01*
G02X272179Y384876I1789J-1449D01*
G37*
G36*
G01X479900Y481400D02*
X477300D01*
X475800Y482900D01*
Y486800D01*
X475100Y487500D01*
X470400D01*
X469000Y488900D01*
Y491300D01*
X470100Y492400D01*
X475952D01*
G03X476347Y492863I0J400D01*
G02X476326Y493116I1581J259D01*
G01Y494716D01*
G02X476327Y494769I1602J-4D01*
G01X476328Y494773D01*
Y495786D01*
X474518Y497595D01*
Y498396D01*
X472118D01*
Y509868D01*
X479786D01*
X480198Y510281D01*
Y511809D01*
X480200Y511810D01*
Y514200D01*
X481200Y515200D01*
X482130D01*
X482168Y515216D01*
G02X484232I1032J-2388D01*
G01X484270Y515200D01*
X493200D01*
X495400Y513000D01*
Y512882D01*
X501450Y506833D01*
Y492942D01*
G03X501842Y492542I400J0D01*
G02X502448Y492450I-39J-2302D01*
G01X502561Y492416D01*
X529122Y518978D01*
X529000Y519100D01*
Y520700D01*
X528800Y520900D01*
X525440D01*
X525436D01*
G02X525240I-98J2600D01*
G01X525236D01*
X523600D01*
X522400Y522100D01*
Y525900D01*
X521600Y526700D01*
X512600D01*
X509200Y530100D01*
Y536700D01*
X514100Y541600D01*
Y548800D01*
X511500Y551400D01*
Y553600D01*
X513400Y555500D01*
X519000D01*
X519900Y554600D01*
Y550203D01*
X519913Y550169D01*
G02X520014Y549607I-1500J-560D01*
G01Y548007D01*
G02X520010Y547888I-1601J-6D01*
G01X520003Y547797D01*
X520700Y547100D01*
X522200D01*
X524400Y544900D01*
X531200D01*
X532400Y543700D01*
Y542302D01*
Y542298D01*
G02Y542102I-2600J-98D01*
G01Y542098D01*
Y533800D01*
X537600Y528600D01*
Y521200D01*
X537358Y520958D01*
Y520561D01*
X506315Y489518D01*
G03X506518Y488843I283J-283D01*
G02X507341Y488523I-518J-2550D01*
G01X507388Y488494D01*
X513327D01*
X513354Y488503D01*
G02Y484083I646J-2210D01*
G01X513327Y484092D01*
X507388D01*
X507341Y484063D01*
G02X506629Y483768I-1341J2230D01*
G01X506575Y483755D01*
X505819Y482998D01*
X496688D01*
X492387Y487300D01*
X490100D01*
X489800Y487000D01*
Y484800D01*
X488200Y483200D01*
X481700D01*
X479900Y481400D01*
G37*
G54D114*
X258450Y490700D03*
Y484700D03*
G54D107*
X128918Y307533D03*
X726000Y650700D03*
X720000Y650800D03*
X733000Y650600D03*
X740000D03*
X745413Y854763D03*
G54D104*
X51600Y217000D03*
X33400Y266400D03*
X17100Y311700D03*
X42507Y296616D03*
X109534Y314564D03*
X92682Y331571D03*
X727300Y273200D03*
X668987Y731465D03*
X275500Y415400D03*
X264124Y408219D03*
X258267Y408800D03*
X257184Y421241D03*
X304000Y538500D03*
X308800Y540925D03*
X324400Y570500D03*
X428343Y463067D03*
X435138Y460661D03*
G54D109*
X286982Y828335D03*
X356982D03*
X346982D03*
X336982D03*
X326982D03*
X316982D03*
X306982D03*
X296982D03*
X356982Y818335D03*
X336982D03*
X326982D03*
X366982Y828335D03*
Y818335D03*
G54D112*
X362192Y435223D03*
Y429223D03*
G54D113*
X365700Y435223D03*
Y429223D03*
G54D110*
X377387Y393223D03*
Y399223D03*
G54D105*
X53547Y322486D03*
X182681Y580832D03*
Y560832D03*
G54D111*
X395912Y393223D03*
Y399223D03*
G54D106*
X43000Y354200D03*
G54D103*
X-33503Y269685D03*
G54D108*
X224131Y60520D03*
X226331D03*
X259730Y86726D03*
X48560Y171152D03*
X74600Y179600D03*
X109871Y181599D03*
X74600Y182000D03*
X75988Y183254D03*
X109871Y183799D03*
X75988Y186654D03*
X76000Y198600D03*
Y201000D03*
X222566Y217817D03*
X236514Y218813D03*
X218455Y219298D03*
X220855D03*
X222566Y220017D03*
X193963Y236183D03*
Y238583D03*
Y239783D03*
X193921Y245756D03*
X193963Y246983D03*
X66863Y369783D03*
X106683Y82061D03*
X108883D03*
X32194Y491363D03*
Y494763D03*
X29190Y495966D03*
X39047Y498359D03*
X44547D03*
X29190Y498366D03*
X23194Y491363D03*
X26594D03*
X23194Y494763D03*
X23190Y495966D03*
Y498366D03*
X39047Y505959D03*
Y510459D03*
X39355Y516150D03*
Y518350D03*
X91430Y143435D03*
X94830D03*
Y146835D03*
X153441Y155648D03*
X155841D03*
X143400Y232700D03*
Y235100D03*
X200115Y76633D03*
X206011Y76727D03*
X207512Y76930D03*
X209712D03*
X223902Y135316D03*
X226102D03*
X216013Y135360D03*
X218213D03*
X219900Y135500D03*
X222300D03*
X211000Y137000D03*
X214400D03*
X210300Y170200D03*
X187963Y236183D03*
X178490Y236402D03*
X187963Y238583D03*
X178490Y238602D03*
X187963Y239783D03*
X178490Y240602D03*
Y242802D03*
X179950Y245322D03*
X187921Y245756D03*
X187963Y246983D03*
Y249383D03*
X212534Y379777D03*
X218034D03*
X214192Y401333D03*
X199847Y405374D03*
X203247D03*
X204467Y405483D03*
X206867D03*
X204467Y411483D03*
X206867D03*
X199847Y414374D03*
X203247D03*
X205588Y416045D03*
X192924Y419763D03*
X196324D03*
X205441Y385059D03*
X208841D03*
X199298Y387364D03*
X201698D03*
X212534Y387377D03*
X218034D03*
X205441Y388459D03*
X208841D03*
X207988Y422045D03*
X206482Y426089D03*
X196324Y428763D03*
X206482Y429489D03*
X231991Y525351D03*
X220877Y526419D03*
X224277D03*
X220877Y529819D03*
X224277D03*
X226491Y529851D03*
X231991D03*
X698139Y758199D03*
X698192Y764172D03*
X276054Y850365D03*
X278454D03*
X230713Y60398D03*
X243367Y67596D03*
X246767D03*
X253841Y382006D03*
Y384406D03*
X253653Y385929D03*
Y388129D03*
X360019Y391855D03*
X363419D03*
X364886D03*
X368286D03*
X369708D03*
X373108D03*
X374410Y393223D03*
X380364D03*
X381848D03*
X384248D03*
X385526D03*
X387926D03*
X389205D03*
X391605D03*
X392925D03*
X398899D03*
X254582Y398133D03*
X336412Y435223D03*
X338812D03*
X340144D03*
X342544D03*
X343814D03*
X346214D03*
X347714D03*
X350114D03*
X351614D03*
X354014D03*
X355514D03*
X357914D03*
X359215D03*
X368632D03*
X369987D03*
X372387D03*
X374264D03*
X376664D03*
X377984D03*
X380384D03*
X381902D03*
X384302D03*
X385900D03*
X388300D03*
X293000Y460800D03*
X339730Y461451D03*
X343130D03*
X344613Y462943D03*
X347013D03*
X352698D03*
X355098D03*
X356812D03*
X359212D03*
X360442D03*
X362842D03*
X364227D03*
X366627D03*
X348745Y462953D03*
X351145D03*
X293000Y464200D03*
X293700Y465400D03*
X244400Y525500D03*
X245562Y526709D03*
X248962D03*
X486337Y527528D03*
Y529728D03*
X486383Y536059D03*
X486113Y544545D03*
Y546745D03*
X524363Y547033D03*
X526563D03*
X522413Y550007D03*
X522252Y551277D03*
Y553677D03*
X473928Y495116D03*
X457663Y515934D03*
Y513734D03*
X452323Y499183D03*
X455720Y495074D03*
X255500Y490700D03*
X261400D03*
X262653Y492234D03*
X266053D03*
X259751Y494268D03*
X265251D03*
X262653Y483234D03*
X266053D03*
X255500Y484700D03*
X261400D03*
X245562Y517709D03*
X248962D03*
X226491Y517751D03*
X231991D03*
X242000Y519500D03*
X244400D03*
X388300Y429223D03*
X385900D03*
X384302D03*
X381902D03*
X380384D03*
X377984D03*
X376664D03*
X374264D03*
X372387D03*
X369987D03*
X368632D03*
X359215D03*
X357914D03*
X355514D03*
X354014D03*
X351614D03*
X350114D03*
X347714D03*
X346214D03*
X343814D03*
X342544D03*
X340144D03*
X338812D03*
X336412D03*
X373108Y400855D03*
X369708D03*
X368286D03*
X364886D03*
X363419D03*
X360019D03*
X398899Y399223D03*
X392925D03*
X391605D03*
X389205D03*
X387926D03*
X385526D03*
X384248D03*
X381848D03*
X380364D03*
X374410D03*
X344613Y468943D03*
X347013D03*
X352698D03*
X355098D03*
X356812D03*
X359212D03*
X360442D03*
X362842D03*
X364227D03*
X366627D03*
X348745Y468953D03*
X351145D03*
X339730Y470451D03*
X343130D03*
X306474Y474088D03*
Y477488D03*
X302000Y460800D03*
Y464200D03*
X299700Y465400D03*
Y467800D03*
X297474Y474088D03*
Y477488D03*
X649600Y528400D03*
G54D102*
X-59094Y277559D03*
%LPD*%
G75*
G36*
G01X489800Y492400D02*
X489600Y492600D01*
Y493111D01*
X489602Y493126D01*
G03X489620Y493361I-1584J239D01*
G01Y494961D01*
G03X489602Y495196I-1602J-4D01*
G01X489600Y495211D01*
Y496847D01*
X489603Y496864D01*
G03X489624Y497127I-1580J259D01*
G01Y498727D01*
G03X489603Y498990I-1601J4D01*
G01X489600Y499007D01*
Y500582D01*
Y500589D01*
G03X489604Y500702I-1597J113D01*
G01Y502302D01*
G03X489600Y502415I-1601J0D01*
G01Y502422D01*
Y503200D01*
X492900Y506500D01*
X495015D01*
X496746Y504768D01*
Y492946D01*
X496200Y492400D01*
X489800D01*
G37*
%LPC*%
G75*
G36*
G01X492403Y500702D02*
Y499902D01*
X492423Y499527D01*
Y498727D01*
X491623D01*
Y499527D01*
X491603Y499902D01*
Y500702D01*
X492403D01*
G37*
G54D108*
X492018Y495361D03*
X492003Y502702D03*
X492023Y496727D03*
%LPD*%
G75*
G54D100*
G01X6944Y414616D02*
X8068Y413492D01*
X27515D01*
G01X23922Y415548D02*
X23466Y415092D01*
X8873D01*
X7699Y416266D01*
Y423688D01*
X8149Y424138D01*
X9456D01*
X9906Y423688D01*
Y417604D01*
X10356Y417154D01*
X12568D01*
X13152Y417738D01*
Y420115D01*
X14022Y420985D01*
X21326D01*
X21724Y420587D01*
Y418880D01*
X22348Y418256D01*
X23948D01*
X24348Y418656D01*
Y420232D01*
X24748Y420632D01*
X25548D01*
X25948Y420232D01*
Y418656D01*
X26348Y418256D01*
X27148D01*
X27548Y418656D01*
Y420232D01*
X27948Y420632D01*
X28748D01*
X29148Y420232D01*
Y418656D01*
X29548Y418256D01*
X30348D01*
X30748Y418656D01*
Y420232D01*
X31148Y420632D01*
X31948D01*
X32348Y420232D01*
Y418656D01*
X32748Y418256D01*
X33548D01*
X33948Y418656D01*
Y420232D01*
X34348Y420632D01*
X35148D01*
X35548Y420232D01*
Y418656D01*
X35948Y418256D01*
X36748D01*
X37148Y418656D01*
Y420232D01*
X37548Y420632D01*
X38348D01*
X38748Y420232D01*
Y418656D01*
X39148Y418256D01*
X39948D01*
X40348Y418656D01*
Y420232D01*
X40748Y420632D01*
X41548D01*
X41948Y420232D01*
Y418656D01*
X42348Y418256D01*
X43148D01*
X43548Y418656D01*
Y420232D01*
X43948Y420632D01*
X44748D01*
X45148Y420232D01*
Y418656D01*
X45548Y418256D01*
X46348D01*
X46748Y418656D01*
Y420232D01*
X47148Y420632D01*
X47948D01*
X48348Y420232D01*
Y418656D01*
X48748Y418256D01*
X49548D01*
X49948Y418656D01*
Y420232D01*
X50348Y420632D01*
X51148D01*
X51548Y420232D01*
Y418656D01*
X51948Y418256D01*
X52748D01*
X53148Y418656D01*
Y420232D01*
X53548Y420632D01*
X54348D01*
X54748Y420232D01*
Y418656D01*
X55148Y418256D01*
X57088D01*
X60263Y421431D01*
X64127D01*
X64390Y421694D01*
X68451D01*
X68901Y422144D01*
Y423942D01*
G01X6855Y436844D02*
X10515D01*
G01X6750Y425868D02*
X11830D01*
X12937Y424761D01*
X21399D01*
X22989Y426351D01*
X25725D01*
X27315Y424761D01*
X58516D01*
X61634Y427879D01*
X64964D01*
G01X7180Y449205D02*
X25415D01*
G01X43100Y103450D02*
X35879D01*
X30854Y98425D01*
G01X22980D02*
X19300Y94745D01*
Y88300D01*
X21000Y86600D01*
X34562D01*
X38262Y82900D01*
X45150D01*
G01D02*
Y85030D01*
X43980Y86200D01*
G01X43100Y106950D02*
Y110100D01*
X42700Y110500D01*
G01X45050Y89400D02*
X46950Y87500D01*
X52158D01*
X54855Y84803D01*
X58059D01*
G01X45050Y89400D02*
X32005D01*
X30854Y90551D01*
G01X45050Y93600D02*
X47250Y95800D01*
X52600D01*
X55727Y92673D01*
X58059D01*
G01X45050Y93600D02*
X44850Y93800D01*
X26229D01*
X22980Y90551D01*
G01X67300Y103350D02*
Y107200D01*
G01X63000Y103350D02*
Y107200D01*
X63100Y107300D01*
G01X79600Y91500D02*
X79400Y91300D01*
X77300D01*
X76708Y90708D01*
X74359D01*
G01X48550Y93600D02*
X51700D01*
X51800Y93500D01*
G01X79500Y85700D02*
X78432Y86768D01*
X74359D01*
G01X48550Y89400D02*
X51400D01*
X51900Y89900D01*
G01X67300Y99850D02*
X71250D01*
X71800Y100400D01*
G01X67300Y99850D02*
Y89800D01*
X64268Y86768D01*
X58059D01*
G01X63000Y99850D02*
X60550D01*
X58800Y101600D01*
G01X63000Y99850D02*
Y93000D01*
X60708Y90708D01*
X58059D01*
G01X74359Y84803D02*
X70897D01*
X70200Y85500D01*
Y92300D01*
X70573Y92673D01*
X74359D01*
G01X77200Y95500D02*
X75500D01*
X74373Y94373D01*
Y92673D01*
X74359D01*
G01X50500Y243100D02*
X50563D01*
X60100Y233563D01*
Y205500D01*
X69100Y196500D01*
Y193550D01*
G01X41142Y155669D02*
X29600Y167211D01*
Y200100D01*
G01X41142Y135669D02*
X26100Y150711D01*
Y187300D01*
G01X41142Y145669D02*
X27900Y158911D01*
Y191000D01*
X27800Y191100D01*
G01X74700Y191700D02*
X73300Y190300D01*
X67400D01*
X66540Y189440D01*
Y187050D01*
G01X70675Y145000D02*
Y134665D01*
G01Y155935D02*
Y145000D01*
G01X70636Y272953D02*
X75521Y268068D01*
X82163D01*
G01X67113Y237683D02*
X67213Y237783D01*
X71763D01*
X78408Y244428D01*
X82163D01*
G01X67013Y242083D02*
X73763D01*
X78078Y246398D01*
X82163D01*
G01X59196Y242114D02*
X61265Y244183D01*
X73563D01*
X77748Y248368D01*
X82163D01*
G01X67113Y246283D02*
X73363D01*
X77418Y250338D01*
X82163D01*
G01X67113Y250483D02*
X75163D01*
X76988Y252308D01*
X82163D01*
G01X59313Y251483D02*
X60413Y252583D01*
X75000D01*
X76325Y253908D01*
X81793D01*
X82163Y254278D01*
G01X66913Y254683D02*
X67413Y254183D01*
X74337D01*
X76402Y256248D01*
X82163D01*
G01X59313Y258883D02*
X61413Y256783D01*
X64552D01*
X64853Y256483D01*
X68779D01*
X69450Y255812D01*
X73703D01*
X76109Y258218D01*
X82163D01*
G01X66913Y258783D02*
X67613Y258083D01*
X69442D01*
X70113Y257412D01*
X73040D01*
X75816Y260188D01*
X82163D01*
G01X66413Y272683D02*
X67236Y273506D01*
Y274362D01*
X69227Y276353D01*
X72045D01*
X74420Y273978D01*
X82163D01*
G01X66913Y262883D02*
X67803Y263773D01*
X74938D01*
X75293Y264128D01*
X82163D01*
G01X59313Y267083D02*
X62513Y270283D01*
X67163D01*
X68836Y271956D01*
Y273699D01*
X69890Y274753D01*
X71382D01*
X74052Y272083D01*
X82088D01*
X82163Y272008D01*
G01X66913Y267083D02*
X67531Y267701D01*
X73397D01*
X75000Y266098D01*
X82163D01*
G01X72915Y261033D02*
X74040Y262158D01*
X82163D01*
G01X72519Y219284D02*
X68584D01*
X68200Y218900D01*
G01X73943Y213410D02*
X69390D01*
X68200Y214600D01*
Y218900D01*
G01X76019Y219284D02*
Y222534D01*
G01X66413Y276783D02*
X67394D01*
X68564Y277953D01*
X72708D01*
X74713Y275948D01*
X82163D01*
G01X58913Y276783D02*
X61360Y279230D01*
X67577D01*
X67901Y279553D01*
X73371D01*
X75006Y277918D01*
X82163D01*
G01X66546Y281630D02*
X68382D01*
X68859Y281153D01*
X74034D01*
X75299Y279888D01*
X82163D01*
G01X66546Y285730D02*
X69523Y282753D01*
X74697D01*
X75592Y281858D01*
X82163D01*
G01X58913Y285083D02*
X60568Y286738D01*
X60659D01*
X62051Y288130D01*
X67594D01*
X71371Y284353D01*
X75360D01*
X75885Y283828D01*
X82163D01*
G01X66851Y290678D02*
X67309D01*
X72034Y285953D01*
X76023D01*
X76178Y285798D01*
X82163D01*
G01X66851Y294778D02*
X67726D01*
X74736Y287768D01*
X82163D01*
G01X64055Y389700D02*
X64964Y390609D01*
Y392446D01*
G01X74544Y414071D02*
X74778D01*
X76775Y416068D01*
G01X70779Y402387D02*
X72649Y404257D01*
X72838D01*
G01X67527Y381818D02*
X64642Y378933D01*
X50963D01*
G01D02*
X50117D01*
X47817Y376633D01*
X22399D01*
X22385Y376619D01*
X20645D01*
X20631Y376633D01*
X9350D01*
X8789Y376072D01*
G01X14422Y411528D02*
Y409714D01*
X14022Y409314D01*
X12037D01*
X11637Y408914D01*
Y408114D01*
X12037Y407714D01*
X14022D01*
X14422Y407314D01*
Y406514D01*
X14022Y406114D01*
X12037D01*
X11637Y405714D01*
Y404914D01*
X12037Y404514D01*
X14022D01*
X14422Y404114D01*
Y403314D01*
X14022Y402914D01*
X12037D01*
X11637Y402514D01*
Y401714D01*
X12037Y401314D01*
X14022D01*
X14422Y400914D01*
Y400114D01*
X14022Y399714D01*
X12037D01*
X11637Y399314D01*
Y398514D01*
X12037Y398114D01*
X14022D01*
X14422Y397714D01*
Y396914D01*
X14022Y396514D01*
X12037D01*
X11637Y396114D01*
Y395314D01*
X12037Y394914D01*
X14022D01*
X14422Y394514D01*
Y393714D01*
X14022Y393314D01*
X12037D01*
X11637Y392914D01*
Y392114D01*
X12037Y391714D01*
X14022D01*
X14422Y391314D01*
Y390514D01*
X14022Y390114D01*
X12037D01*
X11637Y389714D01*
Y388914D01*
X12037Y388514D01*
X14022D01*
X14422Y388114D01*
Y387314D01*
X14022Y386914D01*
X12037D01*
X11637Y386514D01*
Y385714D01*
X12037Y385314D01*
X14022D01*
X14422Y384914D01*
Y384114D01*
X14022Y383714D01*
X12037D01*
X11637Y383314D01*
Y382514D01*
X12037Y382114D01*
X14022D01*
X14422Y381714D01*
Y379169D01*
X14872Y378719D01*
X21515D01*
G01X68901Y420005D02*
X67301Y418405D01*
X60354D01*
X54668Y412719D01*
X38483D01*
X37756Y413446D01*
X31791D01*
X29036Y410691D01*
Y379169D01*
X28586Y378719D01*
X21515D01*
G01X32141Y407501D02*
X30694Y406054D01*
Y380099D01*
X31755Y379038D01*
X34015D01*
G01X64964Y412131D02*
X62352Y409519D01*
X42306D01*
X38265Y405478D01*
Y399410D01*
X37865Y399010D01*
X33990D01*
X33590Y398610D01*
Y397810D01*
X33990Y397410D01*
X37865D01*
X38265Y397010D01*
Y396210D01*
X37865Y395810D01*
X33990D01*
X33590Y395410D01*
Y394610D01*
X33990Y394210D01*
X37865D01*
X38265Y393810D01*
Y393010D01*
X37865Y392610D01*
X33990D01*
X33590Y392210D01*
Y391410D01*
X33990Y391010D01*
X37865D01*
X38265Y390610D01*
Y389810D01*
X37865Y389410D01*
X33990D01*
X33590Y389010D01*
Y388210D01*
X33990Y387810D01*
X37865D01*
X38265Y387410D01*
Y386610D01*
X37865Y386210D01*
X33990D01*
X33590Y385810D01*
Y385010D01*
X33990Y384610D01*
X37865D01*
X38265Y384210D01*
Y380441D01*
X36862Y379038D01*
X34015D01*
G01X31808Y410684D02*
X32970Y411846D01*
X36699D01*
X37426Y411119D01*
X54980D01*
X59929Y416068D01*
X64964D01*
G01X46763Y390533D02*
X46163Y389933D01*
X40915D01*
G01D02*
Y390695D01*
X44653Y394433D01*
X46763D01*
G01D02*
X44463Y396733D01*
Y398887D01*
X45809Y400233D01*
X49871D01*
X49878Y400240D01*
X51782D01*
X51789Y400233D01*
X60146D01*
X61326Y401413D01*
X63023D01*
X64230Y402620D01*
X66100D01*
X67737Y404257D01*
X68901D01*
G01X74817Y409752D02*
Y410173D01*
X76775Y412131D01*
G01X52081Y407029D02*
X52177Y406933D01*
X63703D01*
X64964Y408194D01*
G01X70882Y409794D02*
X71019Y409931D01*
Y410312D01*
X72838Y412131D01*
G01X66938Y410045D02*
X68901Y412008D01*
Y412131D01*
G01X64964Y420005D02*
X64771Y419812D01*
X60629D01*
X56936Y416119D01*
X32200D01*
X29573Y413492D01*
X27515D01*
G01X40615Y397833D02*
X44995Y402213D01*
X61755D01*
X63799Y404257D01*
X64964D01*
G01X43512Y406131D02*
X45512Y404131D01*
X62541D01*
X64381Y405971D01*
X66678D01*
X68901Y408194D01*
G01X53976Y389814D02*
X58395D01*
X64964Y396383D01*
G01X74894Y398251D02*
X75175Y398532D01*
Y402657D01*
X76775Y404257D01*
G01X62031Y399713D02*
X62284D01*
X62891Y400320D01*
X64964D01*
G01X74702Y394300D02*
X76775Y396373D01*
Y396383D01*
G01X50900Y369500D02*
X50730Y369670D01*
Y373862D01*
G01D02*
X52001Y375133D01*
X58500D01*
X60933Y377566D01*
X65821D01*
X72838Y384583D01*
Y388509D01*
G01X74869Y406315D02*
X76748Y408194D01*
X76775D01*
G01X78300Y386505D02*
X78397Y386602D01*
Y388521D01*
X80712Y390836D01*
Y392446D01*
G01X64948Y386626D02*
Y388093D01*
X66664Y389809D01*
Y394146D01*
X68901Y396383D01*
G01X71815Y373833D02*
Y382428D01*
X76775Y387388D01*
Y388509D01*
G01X68901Y392446D02*
Y390914D01*
X67201Y389214D01*
Y386474D01*
X65653Y384926D01*
X58926D01*
X57100Y383100D01*
X55500D01*
G01X50963Y390233D02*
Y389973D01*
X52763Y388173D01*
Y385837D01*
X55500Y383100D01*
G01X50830Y394439D02*
X50963Y394306D01*
Y390233D01*
G01X78362Y398337D02*
X76775Y399924D01*
Y400320D01*
G01X77963Y381183D02*
Y381483D01*
X82312Y385832D01*
Y394783D01*
X80712Y396383D01*
G01X70888Y394222D02*
Y394433D01*
X72838Y396383D01*
G01X68901Y388509D02*
Y386251D01*
X63450Y380800D01*
X53800D01*
X52167Y382433D01*
X50963D01*
G01X46863D02*
X40715D01*
G01X50963D02*
X46863D01*
G01X80712Y388509D02*
Y386385D01*
X75715Y381388D01*
Y373115D01*
X74100Y371500D01*
X69848D01*
X67015Y374333D01*
X65763D01*
G01X61563D02*
X59533D01*
X57900Y372700D01*
G01X65763Y374333D02*
X61563D01*
G01X74836Y453477D02*
Y453441D01*
X76775Y451502D01*
G01X59980Y482517D02*
X60846Y483383D01*
X64579D01*
X64964Y482998D01*
G01X67112Y481066D02*
X68901Y479277D01*
Y479061D01*
G01X70488Y465291D02*
X72466Y463313D01*
X72838D01*
G01X74450Y457429D02*
X74785D01*
X76775Y455439D01*
G01X70713Y461504D02*
Y461501D01*
X72838Y459376D01*
G01X70908Y457771D02*
X72838Y455841D01*
Y455439D01*
G01X24315Y472668D02*
X24792Y473145D01*
X31305D01*
X31931Y472519D01*
X40339D01*
X40381Y472477D01*
G01X64964Y475124D02*
X52384D01*
X52168Y475340D01*
X50465D01*
X48786Y473661D01*
X41565D01*
X40381Y472477D01*
G01X70898Y418271D02*
X70997D01*
X72731Y420005D01*
X72838D01*
G01X61038Y424878D02*
X62392D01*
X63363Y425849D01*
X69205D01*
X71235Y427879D01*
X72838D01*
G01X74726Y425594D02*
X74829Y425697D01*
Y425933D01*
X76775Y427879D01*
G01X46853Y441796D02*
X65395D01*
X67227Y443628D01*
X68901D01*
G01X70809Y438057D02*
X70905D01*
X72538Y439690D01*
X72838D01*
G01X43088Y438073D02*
X45918D01*
X48100Y435891D01*
X62752D01*
X64214Y437353D01*
X64890D01*
X66427Y438890D01*
X67228Y439690D01*
X68901D01*
G01X45486Y456341D02*
Y456439D01*
X48423Y459376D01*
X64964D01*
G01X38566Y451290D02*
X39278D01*
X41090Y453102D01*
X43015D01*
G01X68901Y451502D02*
X67301Y453102D01*
X43015D01*
G01X42312Y463368D02*
X46194Y467250D01*
X64964D01*
G01X74780Y429794D02*
Y429821D01*
X76775Y431816D01*
G01X29472Y428016D02*
X60539D01*
X62002Y429479D01*
X67301D01*
X68901Y427879D01*
G01X13062Y429279D02*
X13285Y429056D01*
X23662D01*
G01X64964Y431816D02*
X64440Y431292D01*
X61552D01*
X59993Y429733D01*
X27345D01*
X26668Y429056D01*
X23662D01*
G01X74656Y421838D02*
X74942D01*
X76775Y420005D01*
G01X68901Y435753D02*
X68863D01*
X66857Y433747D01*
X62874D01*
X61818Y432691D01*
X46772D01*
X44997Y434466D01*
X31492D01*
X28009Y437949D01*
X23020D01*
X21915Y436844D01*
X10515D01*
G01X15424Y422722D02*
X15863Y423161D01*
X22063D01*
X22657Y423755D01*
Y423756D01*
X23652Y424751D01*
X25062D01*
X26780Y423033D01*
X51843D01*
X52215Y422661D01*
G01X64964Y423942D02*
X63253Y422231D01*
X57227D01*
X57225Y422233D01*
X52643D01*
X52215Y422661D01*
G01X70857Y433857D02*
X70880Y433880D01*
X70965D01*
X72838Y435753D01*
G01X14147Y438989D02*
Y440101D01*
X11803Y442445D01*
Y444233D01*
G01X74752Y437655D02*
X74829D01*
X76731Y435753D01*
X76775D01*
G01X74437Y473159D02*
X74803D01*
X76775Y471187D01*
G01X15872Y441916D02*
X17111D01*
X18999Y440028D01*
X21015D01*
G01X64964Y439690D02*
X62482Y437208D01*
X58218D01*
X57935Y437491D01*
X48763D01*
X46226Y440028D01*
X21015D01*
G01X74460Y461287D02*
X74864D01*
X76775Y459376D01*
G01X78793Y445704D02*
Y445654D01*
X76775Y443636D01*
Y443628D01*
G01X72838Y475124D02*
X70868Y477094D01*
G01X23748Y436249D02*
X25299D01*
X25929Y435619D01*
X27293D01*
G01X26611Y441743D02*
X28496Y443628D01*
X64964D01*
G01X70909Y469595D02*
X71024D01*
X72838Y467781D01*
Y467250D01*
G01X30513Y437850D02*
X32297Y436066D01*
X45661D01*
X47436Y434291D01*
X62285D01*
X63747Y435753D01*
X64964D01*
G01X74702Y469183D02*
X76635Y467250D01*
X76775D01*
G01X37420Y461517D02*
X45815D01*
G01X64964Y463313D02*
X59423D01*
X57627Y461517D01*
X45815D01*
G01X31517Y445328D02*
X31555Y445366D01*
X70843D01*
X72581Y443628D01*
X72838D01*
G01Y471187D02*
X70868Y473157D01*
G01X28472Y447107D02*
X28930Y447565D01*
X64964D01*
G01X48298Y454813D02*
X48672Y455187D01*
X64712D01*
X64964Y455439D01*
G01X47307Y465104D02*
X66061D01*
X67852Y463313D01*
X68901D01*
G01X64964Y451502D02*
X62667Y449205D01*
X25415D01*
G01X29064Y471345D02*
X29496Y470913D01*
X36641D01*
X37421Y470133D01*
X41652D01*
X43236Y471717D01*
X51919D01*
X52449Y471187D01*
X64964D01*
G01Y479061D02*
X55906D01*
X55295Y479672D01*
G01D02*
X51754D01*
X51515Y479433D01*
G01X70602Y453533D02*
X70807D01*
X72838Y451502D01*
G01X76775Y475124D02*
X74805Y477094D01*
G01X72838Y479061D02*
X70868Y481031D01*
G01X74598Y485021D02*
Y484758D01*
X72838Y482998D01*
G01X20928Y453864D02*
X17228D01*
G01D02*
X8788D01*
G01X74695Y449260D02*
X76390Y447565D01*
X76775D01*
G01X68901Y467250D02*
X66900Y469251D01*
X50297D01*
X49931Y469617D01*
X47315D01*
G01X21300Y468000D02*
X22513Y469213D01*
X36078D01*
X36758Y468533D01*
X42315D01*
X43399Y469617D01*
X47315D01*
G01X44515Y482933D02*
X47015Y485433D01*
X54965D01*
X55115Y485583D01*
X59063D01*
G01D02*
X59663Y484983D01*
X61163D01*
X63115Y486935D01*
X64964D01*
G01X55470Y529198D02*
X56944Y530672D01*
G03X57267Y531452I-780J780D01*
G03X57300Y531800I-1831J349D01*
G01Y533200D01*
G02X58599Y536339I4439J1D01*
G01X67627Y545367D01*
G02X72082Y547211I4454J-4456D01*
G01X73211D01*
X73600Y547600D01*
X74711D01*
X75100Y547211D01*
X75991D01*
X76431Y547651D01*
X77491D01*
X77931Y547211D01*
X79163D01*
X79603Y547651D01*
X80663D01*
X81103Y547211D01*
X82443D01*
X82883Y547651D01*
X83943D01*
X84383Y547211D01*
X85708D01*
X86148Y547651D01*
X87208D01*
X87648Y547211D01*
X88753D01*
G03X95517Y550013I-1J9567D01*
G01X101218Y555714D01*
X101227Y555725D01*
X101261Y555759D01*
G03X102916Y559753I-3994J3995D01*
G01Y567913D01*
G03X101452Y571448I-5000J0D01*
G01X98190Y574710D01*
G03X94655Y576174I-3535J-3536D01*
G01X90565D01*
G03X89385Y575685I0J-1668D01*
G02X88207Y575197I-1178J1178D01*
G01X85000D01*
G01X66497Y525105D02*
X67681Y526290D01*
G03X68100Y527300I-1010J1011D01*
G01Y529529D01*
G02X69944Y533984I6300J1D01*
G01X77387Y541427D01*
G02X81842Y543271I4454J-4456D01*
G01X91474D01*
G03X96066Y545174I-2J6497D01*
G01X107036Y556144D01*
G03X108500Y559679I-3536J3535D01*
G01Y575286D01*
X108060Y575726D01*
Y576926D01*
X108500Y577366D01*
Y578566D01*
X108060Y579006D01*
Y580191D01*
X108500Y580631D01*
Y581783D01*
X108060Y582223D01*
Y583363D01*
X108500Y583803D01*
Y585003D01*
X108060Y585443D01*
Y586643D01*
X108500Y587083D01*
Y593529D01*
G03X107036Y597064I-5000J0D01*
G01X104264Y599836D01*
G03X100729Y601300I-3535J-3536D01*
G01X89941D01*
G03X88847Y600847I0J-1548D01*
G02X87753Y600394I-1094J1095D01*
G01X85000D01*
G01X69970Y525089D02*
G02X69400Y526465I1376J1376D01*
G01Y529529D01*
G02X70864Y533064I5000J0D01*
G01X78307Y540507D01*
G02X81842Y541971I3535J-3536D01*
G01X91475D01*
G03X96986Y544254I-2J7798D01*
G01X107956Y555224D01*
G03X109800Y559679I-4456J4454D01*
G01Y593529D01*
G03X107956Y597984I-6300J1D01*
G01X105184Y600756D01*
G03X100729Y602600I-4454J-4456D01*
G01X90268D01*
G02X89128Y603072I0J1613D01*
G03X87988Y603544I-1140J-1141D01*
G01X85000D01*
G01X77453Y529374D02*
X78969Y530890D01*
X79133Y531053D01*
G03X79817Y532706I-1653J1652D01*
G01Y534373D01*
G02X80700Y536506I3018J0D01*
G01X81069Y536875D01*
G02X84046Y538107I2976J-2978D01*
G01X91938D01*
G03X96240Y539889I0J6084D01*
G01X111608Y555257D01*
G03X113361Y559489I-4232J4232D01*
G01Y586683D01*
X112921Y587123D01*
Y588263D01*
X113361Y588703D01*
Y589903D01*
X112921Y590343D01*
Y591543D01*
X113361Y591983D01*
Y593183D01*
X112921Y593623D01*
Y594808D01*
X113361Y595248D01*
Y599268D01*
G03X111897Y602803I-5000J0D01*
G01X105364Y609336D01*
G03X101829Y610800I-3535J-3536D01*
G01X90676D01*
G03X89522Y610322I0J-1632D01*
G02X88366Y609843I-1156J1155D01*
G01X85000D01*
G01X59007Y529278D02*
G02X58600Y530261I983J983D01*
G01Y533200D01*
G02X59519Y535419I3138J0D01*
G01X68547Y544447D01*
G02X72082Y545911I3535J-3536D01*
G01X88752D01*
G03X96437Y549093I2J10868D01*
G01X102128Y554784D01*
G03X102147Y554805I-202J201D01*
G01X102181Y554839D01*
G03X104216Y559752I-4914J4913D01*
G01Y567913D01*
G03X102372Y572368I-6300J1D01*
G01X99110Y575630D01*
G03X94655Y577474I-4454J-4456D01*
G01X90343D01*
G02X89290Y577910I0J1490D01*
G03X88235Y578347I-1055J-1055D01*
G01X85000D01*
G01X43515Y490933D02*
X46020Y488428D01*
X62520D01*
X64964Y490872D01*
G01X70227Y517540D02*
X70220Y517533D01*
Y513505D01*
G03X71154Y511250I3189J0D01*
G01X71399Y511005D01*
G03X75020Y509505I3621J3621D01*
G01X78826D01*
G02X80999Y508605I0J-3073D01*
G03X85156Y506883I4157J4157D01*
G01X94263D01*
G02X98018Y505327I-1J-5311D01*
G01X98163Y505183D01*
X105210Y498136D01*
G02X105975Y496785I-2060J-2058D01*
G02X106063Y496077I-2824J-710D01*
G01Y495046D01*
G02X104334Y490872I-5903J0D01*
G01X69970Y521589D02*
G02X70227Y520969I-620J-620D01*
G01Y517540D01*
G01X59232Y521602D02*
G03X59101Y521286I316J-316D01*
G01Y514463D01*
G03X60699Y510605I5456J0D01*
G03X73736Y505205I13037J13037D01*
G01X76868D01*
G02X78799Y504405I0J-2731D01*
G03X80542Y503683I1743J1743D01*
G01X93464D01*
G02X96021Y502624I-1J-3620D01*
G01X96161Y502485D01*
X101145Y497501D01*
G02X102063Y495285I-2216J-2216D01*
G01Y494383D01*
G02X100758Y491234I-4454J1D01*
G01X100397Y490872D01*
G01X59007Y525778D02*
Y522145D01*
G03X59232Y521602I768J0D01*
G01X51015Y491933D02*
X52218Y490730D01*
X56327D01*
X60406Y494809D01*
X68901D01*
G01X49815Y502633D02*
X50115Y502333D01*
X51615D01*
X56227Y497721D01*
X69926D01*
X72838Y494809D01*
G01X74870Y488789D02*
X74869D01*
X73015Y486935D01*
X72838D01*
G01X52315Y497433D02*
X52415D01*
X53222Y496626D01*
X69489D01*
X71063Y495052D01*
Y492647D01*
X72838Y490872D01*
G01X47790Y524850D02*
G02X47247Y526161I1311J1311D01*
G01Y533176D01*
G02X48331Y535791I3699J-1D01*
G01X62956Y550416D01*
G02X65571Y551500I2616J-2615D01*
G01X89929D01*
G03X94384Y553344I1J6300D01*
G01X95922Y554882D01*
G03X97766Y559337I-4456J4454D01*
G01Y562664D01*
G03X96302Y566198I-5000J-1D01*
G01X95964Y566536D01*
G03X92429Y568000I-3535J-3536D01*
G01X89735D01*
G02X88651Y568449I0J1533D01*
G03X87567Y568898I-1084J-1084D01*
G01X85000D01*
G01X44031Y524946D02*
X45284Y526198D01*
G03X45947Y527800I-1602J1601D01*
G01Y533176D01*
G02X47411Y536711I5000J0D01*
G01X62036Y551336D01*
G02X65571Y552800I3535J-3536D01*
G01X72186D01*
X72626Y553240D01*
X73826D01*
X74266Y552800D01*
X75466D01*
X75906Y553240D01*
X77091D01*
X77531Y552800D01*
X78683D01*
X79123Y553240D01*
X80263D01*
X80703Y552800D01*
X81903D01*
X82343Y553240D01*
X83543D01*
X83983Y552800D01*
X85183D01*
X85623Y553240D01*
X86808D01*
X87248Y552800D01*
X89929D01*
G03X93464Y554264I0J5000D01*
G01X95002Y555802D01*
G03X96466Y559337I-3536J3535D01*
G01Y562663D01*
G03X95382Y565278I-3699J-1D01*
G01X95044Y565616D01*
G03X92429Y566700I-2616J-2615D01*
G01X89773D01*
G03X88624Y566224I0J-1625D01*
G02X87475Y565748I-1149J1149D01*
G01X85000D01*
G01X47952Y517237D02*
Y512305D01*
G03X49545Y508459I5439J0D01*
G01X50699Y507305D01*
G03X65667Y501105I14968J14968D01*
G01X74595D01*
G02X77335Y499970I0J-3875D01*
G03X80199Y498783I2865J2864D01*
G01X94514D01*
G02X96883Y497802I1J-3349D01*
G01X97246Y497439D01*
G02X98346Y494783I-2657J-2656D01*
G02X96914Y491326I-4889J0D01*
G01X96460Y490872D01*
G01X47790Y521350D02*
Y517628D01*
G03X47952Y517237I553J0D01*
G01X43905Y517250D02*
Y514448D01*
G03X44610Y513743I705J0D01*
G01X45956D01*
G02X46652Y513047I0J-696D01*
G01Y512306D01*
G03X48625Y507539I6740J-2D01*
G01X49779Y506385D01*
G03X65666Y499805I15887J15889D01*
G01X74594D01*
G02X76415Y499050I0J-2574D01*
G03X80199Y497484I3782J3785D01*
G01Y497483D01*
X94514D01*
G02X95963Y496883I0J-2049D01*
G01X96255Y496591D01*
G02X96460Y496096I-495J-495D01*
G01Y494809D01*
G01X44031Y521446D02*
X45471Y520006D01*
G02X45886Y519004I-1002J-1002D01*
G01Y518234D01*
G02X45666Y517704I-748J0D01*
G01X45549Y517587D01*
G02X44737Y517250I-813J812D01*
G01X43905D01*
G01X55229Y521570D02*
Y519496D01*
G03X55929Y518796I700J0D01*
G01X57101D01*
G02X57801Y518096I0J-700D01*
G01Y514464D01*
G03X59779Y509685I6757J-2D01*
G03X73736Y503905I13956J13958D01*
G01X76867D01*
G02X77879Y503485I-1J-1430D01*
G03X78868Y502775I2661J2663D01*
G03X80541Y502383I1673J3373D01*
G01X93463D01*
G02X95102Y501704I-1J-2320D01*
G01X95103Y501702D01*
X95243Y501564D01*
X100026Y496781D01*
G02X100397Y495885I-896J-896D01*
G01Y494809D01*
G01X55470Y525698D02*
X56705Y524462D01*
G02X57119Y523464I-998J-999D01*
G01Y522318D01*
G02X56900Y521789I-748J0D01*
G02X56371Y521570I-529J529D01*
G01X55229D01*
G01X66272Y517540D02*
Y516117D01*
G03X66721Y515033I1533J0D01*
G03X67216Y514828I495J495D01*
G01X68205D01*
G02X68700Y514623I0J-700D01*
G01X68720Y514603D01*
G02X68920Y514120I-483J-483D01*
G01Y513506D01*
G03X70234Y510330I4490J-2D01*
G01X70479Y510085D01*
G03X75019Y508205I4540J4542D01*
G01X78827D01*
G02X80079Y507685I-2J-1772D01*
G03X81965Y506331I5075J5078D01*
G03X85155Y505583I3191J6431D01*
G01X94483D01*
G02X96943Y504564I0J-3479D01*
G01X104323Y497184D01*
G02X104720Y496478I-1062J-1062D01*
G02X104722Y496471I-1442J-416D01*
G01Y495746D01*
G02X104334Y494809I-1325J0D01*
G01X66497Y521605D02*
X68110Y519992D01*
G02X68315Y519497I-495J-495D01*
G01Y518240D01*
G02X67615Y517540I-700J0D01*
G01X66272D01*
G01X77292Y521666D02*
Y520400D01*
G03X77471Y519932I701J0D01*
G01X77719Y519657D01*
G03X78240Y519425I521J469D01*
G01X79375D01*
G02X80075Y518725I0J-700D01*
G01Y515911D01*
G03X81943Y511399I6380J-1D01*
G01X83274Y510068D01*
G03X85895Y508983I2621J2623D01*
G01X95175D01*
G02X99253Y507294I0J-5767D01*
G01X107039Y499507D01*
X107375Y499172D01*
G02X108571Y496283I-2889J-2888D01*
G01Y495533D01*
G02X108271Y494809I-1024J0D01*
G01X77453Y525874D02*
X79093Y524233D01*
G02X79298Y523738I-495J-495D01*
G01Y522366D01*
G02X78598Y521666I-700J0D01*
G01X77292D01*
G01X69523Y567387D02*
X69588Y567322D01*
X75119D01*
X75118Y567323D01*
G01X69555Y564187D02*
X69569Y564173D01*
X75119D01*
X75118Y564174D01*
G01X69599Y601527D02*
X69966D01*
G03X70625Y601679I0J1506D01*
G02X71323Y601968I698J-698D01*
G01X75119D01*
X75118Y601969D01*
G01X69569Y598159D02*
G02X71160Y598818I1591J-1591D01*
G01X75119D01*
X75118Y598819D01*
G01X69388Y576660D02*
X69499Y576771D01*
X75119D01*
X75118Y576772D01*
G01X69450Y573460D02*
X69611Y573621D01*
X75119D01*
X75118Y573622D01*
G01X69569Y608021D02*
G02X70163Y608267I594J-594D01*
G01X75119D01*
X75118Y608268D01*
G01X69496Y611417D02*
X75119D01*
X75118Y611418D01*
G01X69661Y591387D02*
X70793Y592519D01*
X75119D01*
X75118Y592520D01*
G01X66579Y592250D02*
Y591191D01*
X68401Y589369D01*
X75119D01*
X75118Y589370D01*
G01X63125Y592801D02*
Y592103D01*
X69008Y586220D01*
X75119D01*
X75118Y586221D01*
G01X62681Y589462D02*
Y587916D01*
X67525Y583070D01*
X75119D01*
X75118Y583071D01*
G01X69451Y684303D02*
G03X70703Y684721I0J2084D01*
G02X72420Y685432I1717J-1717D01*
G01X75119D01*
X75118Y685433D01*
G01X69451Y681103D02*
G02X72300Y682283I2849J-2849D01*
G01X75119D01*
X75118Y682284D01*
G01X41142Y655669D02*
X41976Y656503D01*
X65314D01*
G01X68340Y665912D02*
Y662840D01*
X65314Y659814D01*
Y656503D01*
G01X41142Y635669D02*
X42511Y634300D01*
X52900D01*
G01X65430Y637798D02*
X59531D01*
X59384Y637651D01*
G01D02*
X56851D01*
X53500Y634300D01*
X52900D01*
G01X69451Y691003D02*
G02X71209Y691731I1758J-1758D01*
G01X75119D01*
X75118Y691732D01*
G01X69474Y694403D02*
G02X70628Y694881I1154J-1154D01*
G01X75119D01*
X75118Y694882D01*
G01X72814Y652628D02*
X74105Y651337D01*
X80191D01*
G01X63757Y647187D02*
X63613D01*
X61300Y649500D01*
X44973D01*
X41142Y645669D01*
G01X79922Y636136D02*
X75143D01*
X72930Y633923D01*
G01X69523Y718313D02*
Y719001D01*
G02X69762Y719578I816J0D01*
G02X70969Y720078I1207J-1207D01*
G01X75119D01*
X75118Y720079D01*
G01X69523Y715113D02*
G02X70001Y716269I1634J1D01*
G01X70228Y716495D01*
G02X71273Y716928I1045J-1045D01*
G01X75119D01*
X75118Y716929D01*
G01X69472Y729385D02*
X69615Y729528D01*
X75118D01*
G01X69548Y726185D02*
G02X70012Y726377I464J-464D01*
G01X75117D01*
X75118Y726378D01*
G01X65912Y752551D02*
X65260D01*
X63300Y754511D01*
X60122D01*
G01X52900Y759300D02*
X55333D01*
X60122Y754511D01*
G01X52900Y759300D02*
X46662D01*
X41142Y753780D01*
G01X65447Y711413D02*
X67087D01*
X68688Y709812D01*
X71294D01*
X72111Y710629D01*
X75119D01*
X75118Y710630D01*
G01X62066Y711051D02*
X63504Y709613D01*
X66624D01*
X68758Y707479D01*
X75119D01*
X75118Y707480D01*
G01X65356Y707010D02*
X65521Y706845D01*
X66657D01*
X69172Y704330D01*
X75119D01*
X75118Y704331D01*
G01X61193Y706973D02*
X66986Y701180D01*
X75119D01*
X75118Y701181D01*
G01X80653Y751154D02*
X76554D01*
X74076Y748676D01*
X73412D01*
G01X64248Y761923D02*
X63725Y761400D01*
X58100D01*
X55720Y763780D01*
X41142D01*
G01X73356Y767193D02*
X74419Y768256D01*
X80464D01*
G01X65856Y771068D02*
X60168D01*
X59800Y770700D01*
G01D02*
X46200D01*
X43120Y773780D01*
X41142D01*
G01X107899Y189286D02*
X112068D01*
X114434Y186920D01*
X115096D01*
G01D02*
Y185100D01*
X114421Y184425D01*
Y182699D01*
G01D02*
X118101D01*
X119300Y181500D01*
G01X91599Y197156D02*
Y203492D01*
X91291Y203800D01*
G01D02*
Y207770D01*
X91178Y207883D01*
G01X149031Y168850D02*
X143932D01*
X142615Y167533D01*
G01X84900Y145300D02*
Y141350D01*
X84650Y141100D01*
G01X82645Y134201D02*
Y139095D01*
X84650Y141100D01*
G01X81443Y209535D02*
X86865D01*
X87100Y209300D01*
G01X91178Y207883D02*
X88517D01*
X87100Y209300D01*
G01X124478Y280855D02*
X124480D01*
X129948Y275387D01*
Y266505D01*
X133783Y262670D01*
X135275D01*
X135523Y262918D01*
X138032D01*
X141636Y259314D01*
Y257200D01*
X154408Y244428D01*
X157763D01*
G01X87227Y242891D02*
X87027Y242691D01*
X83900D01*
X82163Y244428D01*
G01X87698Y246708D02*
X87388Y246398D01*
X82163D01*
G01X91230Y247047D02*
X89769Y248508D01*
X85697D01*
X85557Y248368D01*
X82163D01*
G01X91819Y250396D02*
Y250600D01*
X91224Y251195D01*
X86121D01*
X85264Y250338D01*
X82163D01*
G01X94793Y252595D02*
X94720Y252668D01*
X93910D01*
X93795Y252783D01*
X93778Y252795D01*
X85458D01*
X84971Y252308D01*
X82163D01*
G01X98211Y252758D02*
X96691Y254278D01*
X96524Y254395D01*
X84795D01*
X84678Y254278D01*
X82163D01*
G01X132651Y255357D02*
X117960D01*
X117312Y256005D01*
X115820D01*
X115172Y255357D01*
X97875D01*
X97724Y255508D01*
X97029Y255995D01*
X82416D01*
X82163Y256248D01*
G01X138228Y260175D02*
X137333Y261070D01*
X133120D01*
X128506Y265684D01*
X111592D01*
X103668Y273608D01*
X102341D01*
X101518Y274431D01*
X91359D01*
X89842Y275948D01*
X82163D01*
G01X150666Y243134D02*
Y239637D01*
X150204Y239175D01*
X146117D01*
X145717Y239575D01*
Y240608D01*
X145317Y241008D01*
X144517D01*
X144117Y240608D01*
Y239575D01*
X143717Y239175D01*
X142917D01*
X142517Y239575D01*
Y240608D01*
X142117Y241008D01*
X141317D01*
X140917Y240608D01*
Y239575D01*
X140517Y239175D01*
X139717D01*
X139317Y239575D01*
Y240608D01*
X138917Y241008D01*
X138117D01*
X137717Y240608D01*
Y239575D01*
X137317Y239175D01*
X135717D01*
X134627Y240265D01*
Y253258D01*
X136796Y255427D01*
X138725D01*
X139863Y256565D01*
Y258540D01*
X138228Y260175D01*
G01X124933Y270414D02*
X121803Y267284D01*
X112255D01*
X104331Y275208D01*
X103004D01*
X102181Y276031D01*
X92023D01*
X90136Y277918D01*
X82163D01*
G01X124874Y273953D02*
X119805Y268884D01*
X112918D01*
X104994Y276808D01*
X103667D01*
X102844Y277631D01*
X92686D01*
X90484Y279833D01*
X84648D01*
X84593Y279888D01*
X82163D01*
G01X135592Y257933D02*
X134055Y259470D01*
X132457D01*
X127843Y264084D01*
X100207D01*
X97451Y266840D01*
Y267281D01*
X95101Y269631D01*
X89371D01*
X88964Y270038D01*
X82163D01*
G01X114229Y270684D02*
X110242Y274671D01*
Y279623D01*
X107655Y282210D01*
X98935D01*
X98158Y281433D01*
X85311D01*
X84886Y281858D01*
X82163D01*
G01X112042Y275903D02*
Y275135D01*
X114695Y272484D01*
X115152D01*
X117152Y270484D01*
X118332D01*
X118892Y271043D01*
Y271678D01*
X117873Y272697D01*
X117473D01*
X116419Y273751D01*
Y276537D01*
X109146Y283810D01*
X98139D01*
X97362Y283033D01*
X85974D01*
X85179Y283828D01*
X82163D01*
G01X118219Y274497D02*
X118827Y275105D01*
Y279221D01*
X111038Y287010D01*
X96813D01*
X96036Y286233D01*
X87300D01*
X85765Y287768D01*
X82163D01*
G01X130567Y258051D02*
X127071Y261547D01*
X121163D01*
X120876Y261260D01*
X113558D01*
G01X106381Y259865D02*
X104734Y258218D01*
X82163D01*
G01X103003Y260260D02*
X102931Y260188D01*
X82163D01*
G01X107887Y266647D02*
Y266895D01*
X102774Y272008D01*
X101678D01*
X100855Y272831D01*
X90696D01*
X89549Y273978D01*
X82163D01*
G01X101242Y265901D02*
Y269380D01*
X99391Y271231D01*
X90033D01*
X89256Y272008D01*
X82163D01*
G01X126611Y258265D02*
X124929Y259947D01*
X121826D01*
X121339Y259460D01*
X111097D01*
X108351Y262206D01*
X99822D01*
X95851Y266177D01*
Y266618D01*
X94438Y268031D01*
X86861D01*
X84928Y266098D01*
X82163D01*
G01X134529Y264470D02*
X134537D01*
X134585Y264518D01*
X138695D01*
X143236Y259977D01*
Y257863D01*
X148791Y252308D01*
X157763D01*
G01X137190Y266587D02*
X140566D01*
X146656Y260497D01*
Y259933D01*
X145403Y258679D01*
Y258115D01*
X145971Y257547D01*
X146535D01*
X147788Y258801D01*
X148352D01*
X148920Y258233D01*
Y257669D01*
X147667Y256415D01*
Y255851D01*
X148235Y255283D01*
X148799D01*
X150052Y256537D01*
X150616D01*
X150905Y256248D01*
X157763D01*
G01X131901Y267444D02*
X132844Y268387D01*
X141029D01*
X149228Y260188D01*
X157763D01*
G01X132163Y271041D02*
X133217Y269987D01*
X141692D01*
X147551Y264128D01*
X157763D01*
G01X135308Y276806D02*
Y273588D01*
X137309Y271587D01*
X149653D01*
X151202Y270038D01*
X157763D01*
G01X137690Y273752D02*
X137916Y273978D01*
X157763D01*
G01X119603Y285731D02*
X119975Y285359D01*
X135375D01*
X139820Y280914D01*
X151936D01*
X154850Y283828D01*
X157763D01*
G01X121005Y331729D02*
G03X122841Y336161I-4432J4432D01*
G01Y341004D01*
G03X119718Y348545I-10663J1D01*
G01X119717Y348544D01*
X114677Y353584D01*
G02X102701Y382500I28917J28914D01*
G01X102700D01*
Y389656D01*
G02X103517Y391628I2790J-1D01*
G01X104334Y392446D01*
G01X121255Y327679D02*
Y331479D01*
X121005Y331729D01*
G01X125223Y331655D02*
G02X124141Y334267I2612J2612D01*
G01Y341005D01*
G03X120637Y349464I-11963J0D01*
G01X115597Y354504D01*
G02X104000Y382500I27996J27997D01*
G01Y387703D01*
G02X104334Y388509I1140J0D01*
G01X124973Y327605D02*
Y331405D01*
X125223Y331655D01*
G01X132467Y335856D02*
G03X133980Y339509I-3653J3653D01*
G01Y341832D01*
G03X132745Y344814I-4217J0D01*
G01X115000Y362559D01*
G02X106453Y383200I20642J20638D01*
G01X106452D01*
Y388055D01*
G02X108271Y392446I6210J0D01*
G01X132717Y331706D02*
Y335606D01*
X132467Y335856D01*
G01X136467D02*
G02X135280Y338722I2866J2866D01*
G01Y341832D01*
G03X133665Y345734I-5518J2D01*
G01X115920Y363479D01*
G02X107752Y383200I19721J19720D01*
G01Y387256D01*
G02X108271Y388509I1772J0D01*
G01X136317Y331706D02*
Y335706D01*
X136467Y335856D01*
G01X143603Y331742D02*
X144841Y332979D01*
G03X145226Y333910I-931J930D01*
G03X143866Y337195I-4645J1D01*
G01X143780Y337280D01*
X141334Y339726D01*
G02X139778Y343482I3758J3757D01*
G01Y343483D01*
G03X139757Y343896I-4097J-1D01*
G03X138579Y346380I-4076J-412D01*
G01X114759Y370200D01*
G02X110164Y381300I11101J11097D01*
G01X110163D01*
Y388105D01*
G02X111787Y392024I5543J-1D01*
G01X112208Y392446D01*
G01X143853Y327592D02*
Y331492D01*
X143603Y331742D01*
G01X147560Y331731D02*
X147511Y331779D01*
G02X146526Y333910I2406J2405D01*
G01X146527D01*
G03X144783Y338118I-5946J1D01*
G01X144697Y338202D01*
X144000Y338900D01*
X142254Y340646D01*
G02X141079Y343483I2837J2837D01*
G01Y343484D01*
G03X141051Y344027I-5397J-6D01*
G03X139499Y347300I-5370J-542D01*
G01X115679Y371120D01*
G02X111463Y381300I10180J10179D01*
G01Y387005D01*
G02X112000Y388300I1832J-1D01*
G01X112208Y388509D01*
G01X147553Y327492D02*
Y331724D01*
X147560Y331731D01*
G01X154602Y335814D02*
G03X155941Y339047I-3233J3233D01*
G01Y340002D01*
G03X154983Y342315I-3271J0D01*
G03X150388Y343800I-4595J-6368D01*
G01Y343799D01*
X150038D01*
G02X144282Y346182I-1J8140D01*
G01X118884Y371580D01*
G02X114279Y382700I11120J11119D01*
G01Y388305D01*
G02X115888Y392188I5492J-1D01*
G01X116145Y392446D01*
G01X780514Y342540D02*
X773093D01*
G02X771500Y343200I0J2252D01*
G03X769907Y343860I-1593J-1592D01*
G01X676931D01*
G03X674316Y342776I1J-3699D01*
G01X638986Y307446D01*
G02X634531Y305602I-4454J4456D01*
G01X157753D01*
G02X123280Y319880I-1J48752D01*
G02X122500Y321767I1887J1885D01*
G01Y322517D01*
G03X122205Y323229I-1007J0D01*
G01X121255Y324179D01*
G01X124973Y324105D02*
X124388Y323521D01*
G03X123800Y322100I1421J-1420D01*
G01Y321766D01*
G03X124200Y320800I1366J0D01*
G03X157753Y306902I33553J33553D01*
G01X516485D01*
X516925Y307342D01*
X518125D01*
X518565Y306902D01*
X519765D01*
X520205Y307342D01*
X521405D01*
X521845Y306902D01*
X523045D01*
X523485Y307342D01*
X524685D01*
X525125Y306902D01*
X526325D01*
X526765Y307342D01*
X527965D01*
X528405Y306902D01*
X578405D01*
X578845Y307342D01*
X580045D01*
X580485Y306902D01*
X581685D01*
X582125Y307342D01*
X583325D01*
X583765Y306902D01*
X584965D01*
X585405Y307342D01*
X586605D01*
X587045Y306902D01*
X588245D01*
X588685Y307342D01*
X589885D01*
X590325Y306902D01*
X591525D01*
X591965Y307342D01*
X593165D01*
X593605Y306902D01*
X634531D01*
G03X638066Y308366I0J5000D01*
G01X644287Y314587D01*
Y315209D01*
X645136Y316058D01*
X645758D01*
X646607Y316906D01*
Y317529D01*
X647455Y318377D01*
X648077D01*
X648926Y319226D01*
Y319848D01*
X649774Y320696D01*
X650397D01*
X651245Y321545D01*
Y322167D01*
X652094Y323016D01*
X652716D01*
X673396Y343696D01*
G02X676931Y345160I3535J-3536D01*
G01X696660D01*
X697100Y345600D01*
X698339D01*
X698779Y345160D01*
X700379D01*
X700819Y345600D01*
X702419D01*
X702859Y345160D01*
X704459D01*
X704899Y345600D01*
X706499D01*
X706939Y345160D01*
X708539D01*
X708979Y345600D01*
X710579D01*
X711019Y345160D01*
X712619D01*
X713059Y345600D01*
X714300D01*
X714740Y345160D01*
X770646D01*
G03X771353Y345453I0J999D01*
G01X772087Y346187D01*
G02X772794Y346480I707J-706D01*
G01X780514D01*
G01Y358290D02*
X773251D01*
G02X771645Y358956I1J2272D01*
G01X771644Y358957D01*
G03X770039Y359621I-1605J-1608D01*
G01X683592D01*
G03X680977Y358537I1J-3699D01*
G01X634365Y311925D01*
G02X629910Y310081I-4454J4456D01*
G01X158157D01*
G02X134980Y319680I-2J32777D01*
G02X133800Y322530I2852J2850D01*
G01Y327161D01*
G03X133494Y327900I-1045J0D01*
G03X132755Y328206I-739J-739D01*
G01X132717D01*
G01X136317D02*
X135892Y328030D01*
G03X135280Y327417I435J-1047D01*
G01X135187Y327192D01*
G03X135100Y326757I1047J-436D01*
G01Y322529D01*
X135101Y322530D01*
G03X135900Y320600I2731J0D01*
G03X158157Y311381I22257J22257D01*
G01X518665D01*
X519105Y311821D01*
X520305D01*
X520745Y311381D01*
X521945D01*
X522385Y311821D01*
X523585D01*
X524025Y311381D01*
X525225D01*
X525665Y311821D01*
X526865D01*
X527305Y311381D01*
X528505D01*
X528945Y311821D01*
X530145D01*
X530585Y311381D01*
X580585D01*
X581025Y311821D01*
X582225D01*
X582665Y311381D01*
X583865D01*
X584305Y311821D01*
X585505D01*
X585945Y311381D01*
X587145D01*
X587585Y311821D01*
X588785D01*
X589225Y311381D01*
X590425D01*
X590865Y311821D01*
X592065D01*
X592505Y311381D01*
X629910D01*
G03X633445Y312845I0J5000D01*
G01X644029Y323429D01*
Y324051D01*
X644877Y324899D01*
X645500D01*
X646348Y325748D01*
Y326370D01*
X647197Y327219D01*
X647819D01*
X648667Y328067D01*
Y328690D01*
X649516Y329538D01*
X650138D01*
X650987Y330387D01*
Y331009D01*
X651835Y331857D01*
X652458D01*
X653306Y332706D01*
Y333328D01*
X654155Y334177D01*
X654777D01*
X680057Y359457D01*
G02X683592Y360921I3535J-3536D01*
G01X695980D01*
X696420Y361361D01*
X697620D01*
X698060Y360921D01*
X699260D01*
X699700Y361361D01*
X700900D01*
X701340Y360921D01*
X702540D01*
X702980Y361361D01*
X704180D01*
X704620Y360921D01*
X705820D01*
X706260Y361361D01*
X707460D01*
X707900Y360921D01*
X709021D01*
X709400Y361300D01*
X710521D01*
X710900Y360921D01*
X769899D01*
G03X771473Y361573I0J2226D01*
G02X773047Y362225I1574J-1574D01*
G01X780514D01*
G01X143853Y324092D02*
X144720Y323224D01*
G02X145100Y322308I-916J-917D01*
G01Y319823D01*
G03X145780Y318180I2325J0D01*
G03X154142Y314717I8362J8364D01*
G01X625446D01*
G03X629901Y316561I1J6300D01*
G01X695510Y382170D01*
G02X698125Y383254I2616J-2615D01*
G01X769796D01*
G02X771418Y382582I0J-2294D01*
G03X773040Y381910I1622J1622D01*
G01X780514D01*
G01X147553Y323992D02*
G03X146484Y322017I2784J-2784D01*
G03X146400Y321208I3853J-809D01*
G01Y319824D01*
G03X146700Y319100I1024J0D01*
G03X154143Y316017I7443J7443D01*
G01X461600D01*
X462040Y316457D01*
X463240D01*
X463680Y316017D01*
X464880D01*
X465320Y316457D01*
X466520D01*
X466960Y316017D01*
X468160D01*
X468600Y316457D01*
X469800D01*
X470240Y316017D01*
X520240D01*
X520680Y316457D01*
X521880D01*
X522320Y316017D01*
X523520D01*
X523960Y316457D01*
X525160D01*
X525600Y316017D01*
X526800D01*
X527240Y316457D01*
X528440D01*
X528880Y316017D01*
X530080D01*
X530520Y316457D01*
X531720D01*
X532160Y316017D01*
X582160D01*
X582600Y316457D01*
X583800D01*
X584240Y316017D01*
X585440D01*
X585880Y316457D01*
X587080D01*
X587520Y316017D01*
X588720D01*
X589160Y316457D01*
X590360D01*
X590800Y316017D01*
X592000D01*
X592440Y316457D01*
X593640D01*
X594080Y316017D01*
X625446D01*
G03X628981Y317481I0J5000D01*
G01X641105Y329605D01*
Y330227D01*
X641953Y331076D01*
X642576D01*
X643424Y331924D01*
Y332546D01*
X644273Y333395D01*
X644895D01*
X645744Y334244D01*
Y334866D01*
X646592Y335714D01*
X647214D01*
X648063Y336563D01*
Y337185D01*
X648911Y338034D01*
X649534D01*
X694590Y383090D01*
G02X698125Y384554I3535J-3536D01*
G01X700700D01*
X701679Y384555D01*
X702119Y384994D01*
X703320D01*
X703760Y384555D01*
X704960Y384554D01*
X705399Y384994D01*
X706599D01*
X707040Y384554D01*
X708239D01*
X708680Y384994D01*
X709880D01*
X710319Y384554D01*
X711519Y384555D01*
X711959Y384994D01*
X713160D01*
X713600Y384555D01*
X713601Y384554D01*
X769938D01*
G03X771502Y385202I0J2211D01*
G02X773066Y385850I1564J-1563D01*
G01X780514D01*
G01X117027Y278475D02*
X110092Y285410D01*
X97476D01*
X96699Y284633D01*
X86637D01*
X85472Y285798D01*
X82163D01*
G01X121599Y274869D02*
Y278712D01*
X111701Y288610D01*
X96150D01*
X95373Y287833D01*
X87963D01*
X86058Y289738D01*
X82163D01*
G01X139784Y276432D02*
X151980D01*
X153466Y277918D01*
X157763D01*
G01X142241Y278783D02*
X142384Y278926D01*
X152211D01*
X155143Y281858D01*
X157763D01*
G01X79016Y410283D02*
Y410435D01*
X80712Y412131D01*
G01X158631Y335850D02*
G02X157241Y339206I3356J3356D01*
G01Y340001D01*
G03X155825Y343311I-4571J2D01*
G03X150388Y345099I-5434J-7365D01*
G01X150038D01*
G02X145202Y347102I0J6839D01*
G01X119804Y372500D01*
G02X115579Y382700I10200J10200D01*
G01Y387143D01*
G02X116145Y388509I1932J0D01*
G01X102364Y402287D02*
X104334Y404257D01*
G01X108271Y400320D02*
X106301Y398350D01*
G01X108271Y404257D02*
X106301Y402287D01*
G01X102364Y398350D02*
X104334Y400320D01*
G01X112208Y404257D02*
X110238Y402287D01*
G01X116145Y404257D02*
X114175Y402287D01*
G01X112208Y400320D02*
X110238Y398350D01*
G01X116145Y400320D02*
X114175Y398350D01*
G01X78939Y414083D02*
Y417859D01*
X80712Y419632D01*
Y420005D01*
G01X165635Y339913D02*
X165712Y339989D01*
G03X167000Y343100I-3111J3110D01*
G01Y345100D01*
G03X166166Y347112I-2846J-1D01*
G03X163580Y348183I-2586J-2586D01*
G01X150464D01*
G02X146362Y349881I-1J5801D01*
G01X121702Y374542D01*
G02X118200Y383000I8459J8456D01*
G01X118199D01*
Y387905D01*
G02X120078Y392441I6415J0D01*
G01X120083Y392446D01*
G01X176688Y344153D02*
X177700Y345165D01*
X178000Y345541D01*
Y348776D01*
G03X174800Y351976I-3200J0D01*
G01X151687D01*
G02X148506Y353294I1J4500D01*
G01X123076Y378724D01*
G02X121758Y381906I3182J3182D01*
G01Y387283D01*
G02X123809Y392236I7004J1D01*
G01X124020Y392446D01*
G01X169635Y339913D02*
X169610Y339939D01*
G02X168300Y343100I3161J3162D01*
G01Y345101D01*
G03X167086Y348032I-4146J0D01*
G03X163579Y349483I-3504J-3507D01*
G01X150464D01*
G02X147282Y350801I0J4500D01*
G01X122622Y375462D01*
G02X119499Y383000I7538J7539D01*
G01Y387099D01*
G02X120083Y388509I1994J0D01*
G01X180688Y344153D02*
G02X179300Y345541I0J1388D01*
G01Y348776D01*
G03X174800Y353276I-4500J0D01*
G01X151688D01*
G02X149426Y354214I1J3200D01*
G01X123996Y379644D01*
G02X123058Y381906I2262J2263D01*
G01Y386583D01*
G02X123740Y388228I2327J-1D01*
G01X124020Y388509D01*
G01X187807Y348289D02*
G03X189200Y351652I-3363J3363D01*
G01Y352651D01*
G03X188600Y354100I-2049J0D01*
G01X188173Y354527D01*
G03X184626Y356276I-4349J-4349D01*
G03X183621Y356342I-1007J-7654D01*
G01X153122D01*
G02X149020Y358040I-1J5801D01*
G01X127445Y379615D01*
G02X125747Y383717I4103J4101D01*
G01Y386021D01*
G02X125710Y386316I3535J593D01*
G02X125699Y386667I3573J288D01*
G01Y386995D01*
G02X127957Y392446I7709J0D01*
G01X191807Y348289D02*
X191402Y348694D01*
G02X190482Y351182I2243J2243D01*
G03X190500Y351652I-6038J467D01*
G01Y352650D01*
G03X189520Y355020I-3349J3D01*
G01X189093Y355447D01*
G03X184796Y357565I-5268J-5270D01*
G01X184795D01*
G03X183622Y357642I-1176J-8943D01*
G01X153122D01*
G02X149940Y358960I0J4500D01*
G01X128365Y380535D01*
G02X127047Y383717I3182J3182D01*
G01Y386126D01*
X127030Y386231D01*
G02X126999Y386605I2253J375D01*
G02X127668Y388220I2284J0D01*
G01X127957Y388509D01*
G01X198888Y352449D02*
G03X200500Y356341I-3892J3892D01*
G01Y357393D01*
G03X200000Y358600I-1707J0D01*
G03X194966Y360685I-5034J-5034D01*
G01X154980D01*
G02X150878Y362383I-1J5801D01*
G01X131917Y381341D01*
G02X130219Y385443I4103J4101D01*
G01Y388402D01*
G02X131894Y392446I5719J0D01*
G01X202888Y352449D02*
G02X201800Y355076I2627J2627D01*
G01Y357394D01*
G03X200920Y359520I-3008J0D01*
G03X194965Y361985I-5952J-5955D01*
G01X154980D01*
G02X151798Y363303I0J4500D01*
G01X132837Y382261D01*
G02X131519Y385443I3182J3182D01*
G01Y387604D01*
G02X131894Y388509I1280J0D01*
G01X209930Y356594D02*
X210457Y357122D01*
G03X211383Y359356I-2234J2235D01*
G03X209813Y363146I-5360J0D01*
G01X209512Y363447D01*
G03X207250Y364385I-2263J-2262D01*
G01X156579D01*
G02X152477Y366083I-1J5801D01*
G01X135476Y383084D01*
G02X134156Y386274I3191J3189D01*
G01Y388583D01*
G02X135703Y392318I5282J0D01*
G01X135831Y392446D01*
G01X214030Y356594D02*
X213432Y357192D01*
G02X212683Y359000I1808J1808D01*
G01Y359357D01*
G03X210733Y364066I-6661J0D01*
G01X210432Y364367D01*
G03X207250Y365685I-3182J-3182D01*
G01X156579D01*
G02X153397Y367003I0J4500D01*
G01X136396Y384004D01*
G02X135456Y386274I2271J2270D01*
G01Y387604D01*
G02X135831Y388509I1280J0D01*
G01X221135Y363914D02*
X221249D01*
G03X221444Y363995I0J275D01*
G01X221924Y364475D01*
G03X222484Y365828I-1354J1353D01*
G01Y366525D01*
G03X222129Y367079I-1440J-532D01*
G01X221988Y367220D01*
G03X221889Y367315I-2583J-2593D01*
G03X219400Y368293I-2491J-2683D01*
G01X157271D01*
G02X153169Y369991I-1J5801D01*
G01X138883Y384277D01*
G02X137959Y386509I2235J2232D01*
G01Y388583D01*
G02X139411Y392090I4959J1D01*
G01X139768Y392446D01*
G01X225089Y363907D02*
X224609Y364387D01*
G02X223875Y366159I1772J1772D01*
G03X223049Y367999I-2831J-166D01*
G01X222908Y368140D01*
G03X219400Y369593I-3508J-3508D01*
G01X157271D01*
G02X154089Y370911I0J4500D01*
G01X139803Y385197D01*
G02X139259Y386510I1314J1314D01*
G01Y387280D01*
G02X139768Y388509I1738J0D01*
G01X241728Y360206D02*
X241278Y360657D01*
G03X239000Y361600I-2277J-2278D01*
G01X238196D01*
G02X234381Y363180I1J5397D01*
G01X233684Y363875D01*
G02X232400Y366979I3105J3102D01*
G03X231280Y369680I-3820J-1D01*
G03X225698Y371993I-5583J-5580D01*
G01X158157D01*
G02X154055Y373691I-1J5801D01*
G01X142862Y384885D01*
G02X142151Y386599I1714J1715D01*
G01Y387354D01*
X142105Y387400D01*
Y388583D01*
G02X143705Y392446I5463J0D01*
G01X241728Y364206D02*
X241003Y363481D01*
G02X239600Y362900I-1403J1403D01*
G01X238197D01*
G02X235300Y364100I0J4097D01*
G01X234604Y364795D01*
G02X233700Y366979I2184J2183D01*
G03X232200Y370600I-5121J0D01*
G03X225699Y373293I-6501J-6501D01*
G01X158157D01*
G02X154975Y374611I0J4500D01*
G01X143781Y385805D01*
G02X143451Y386600I795J796D01*
G01Y387354D01*
X143497Y387400D01*
Y388007D01*
G02X143705Y388509I710J0D01*
G01X237455Y371305D02*
X236683Y372076D01*
G03X235688Y372655I-1591J-1590D01*
G03X235091Y372736I-598J-2169D01*
G02X234664Y372828I488J3300D01*
G02X233548Y373392I920J3206D01*
G03X227838Y375757I-5710J-5710D01*
G01X159407D01*
G02X155305Y377455I-1J5801D01*
G01X147480Y385280D01*
G02X146011Y388826I3546J3546D01*
G01Y389111D01*
G02X147642Y392446I5675J-709D01*
G01X237455Y375305D02*
X236676Y374527D01*
G02X234821Y374148I-1214J1214D01*
G02X234398Y374380I760J1888D01*
G03X227837Y377057I-6560J-6698D01*
G01X159407D01*
G02X156225Y378375I0J4500D01*
G01X148190Y386410D01*
G02X147642Y387733I1323J1323D01*
G01Y388509D01*
G01X82459Y413976D02*
Y414321D01*
X80712Y416068D01*
G01X90566Y394383D02*
X90186Y394763D01*
Y404920D01*
X89249Y405857D01*
X86986D01*
X84649Y408194D01*
G01X82663Y402406D02*
X82563D01*
X80712Y404257D01*
G01X133864Y402287D02*
X131894Y404257D01*
G01X86772Y414047D02*
X86663D01*
X84747Y412131D01*
X84649D01*
G01X122053Y402287D02*
X120083Y404257D01*
G01X133864Y398350D02*
X131894Y400320D01*
G01X137801Y398350D02*
X135831Y400320D01*
G01X122053Y398350D02*
X120083Y400320D01*
G01X137801Y402287D02*
X135831Y404257D01*
G01X125990Y402287D02*
X124020Y404257D01*
G01X125990Y398350D02*
X124020Y400320D01*
G01X129927Y402287D02*
X127957Y404257D01*
G01X129927Y398350D02*
X127957Y400320D01*
G01X82663Y398383D02*
X82649D01*
X80712Y400320D01*
G01X141738Y402287D02*
X139768Y404257D01*
G01X141738Y398350D02*
X139768Y400320D01*
G01X145865Y402287D02*
X145675D01*
X143705Y404257D01*
G01X145865Y398350D02*
X145675D01*
X143705Y400320D01*
G01X149488Y402114D02*
Y402411D01*
X147642Y404257D01*
G01X149583Y398383D02*
X149579D01*
X147642Y400320D01*
G01X78798Y433983D02*
X78942D01*
X80712Y435753D01*
G01X82564Y449659D02*
X82573Y449650D01*
Y449641D01*
X84649Y447565D01*
G01X145663Y441483D02*
Y441670D01*
X143705Y443628D01*
G01X78754Y449904D02*
Y449523D01*
X80712Y447565D01*
G01X98288Y441609D02*
X98263Y441634D01*
Y441825D01*
X96460Y443628D01*
G01X147642Y431816D02*
X149612Y429846D01*
G01X149594Y480923D02*
X149504D01*
X147642Y479061D01*
G01X94518Y449186D02*
X92897Y447565D01*
X92523D01*
G01X86768Y449383D02*
X88586Y447565D01*
G01X98427Y484968D02*
X100397Y482998D01*
G01X98427Y481031D02*
X100397Y479061D01*
G01X102364Y481031D02*
X104334Y479061D01*
G01X102364Y484968D02*
X104334Y482998D01*
G01X106301Y484968D02*
X108271Y482998D01*
G01Y479061D02*
X106301Y481031D01*
G01X114175Y484968D02*
X116145Y482998D01*
G01X114175Y481031D02*
X116145Y479061D01*
G01X122053Y484968D02*
X120083Y482998D01*
G01X122053Y481031D02*
X120083Y479061D01*
G01X124020Y482998D02*
X125990Y484968D01*
G01X124020Y479061D02*
X125990Y481031D01*
G01X145567Y453547D02*
X147459Y455439D01*
X147642D01*
G01X145763Y449583D02*
Y449623D01*
X147642Y451502D01*
G01X96460Y431816D02*
X94490Y429846D01*
G01X90463Y425983D02*
Y426002D01*
X88586Y427879D01*
G01X90480Y437608D02*
Y437647D01*
X92523Y439690D01*
G01X78561Y421756D02*
X78576Y421771D01*
Y421806D01*
X80712Y423942D01*
G01X82562Y425980D02*
X82463Y426079D01*
Y426128D01*
X80712Y427879D01*
G01X86505Y425987D02*
X86445Y426047D01*
Y426083D01*
X84649Y427879D01*
G01X90380Y429650D02*
Y429673D01*
X92523Y431816D01*
G01X96460Y439690D02*
X94490Y437720D01*
G01X82681Y430041D02*
X82874D01*
X84649Y431816D01*
G01X78738Y429679D02*
Y429842D01*
X80712Y431816D01*
G01X98334Y429754D02*
X98263Y429683D01*
Y429682D01*
X96460Y427879D01*
G01X100397Y439690D02*
X98427Y437720D01*
G01X94369Y425977D02*
X94363Y425983D01*
Y426039D01*
X92523Y427879D01*
G01X82677Y433595D02*
Y433781D01*
X84649Y435753D01*
G01X96460D02*
X94490Y433783D01*
G01X141738Y481031D02*
X139768Y479061D01*
G01X82663Y457486D02*
X84649Y455500D01*
Y455439D01*
G01X141738Y484968D02*
X139768Y482998D01*
G01X98433Y449125D02*
X98313Y449245D01*
Y449649D01*
X96460Y451502D01*
G01X137801Y481031D02*
X135831Y479061D01*
G01X102600Y425983D02*
X100704Y427879D01*
X100397D01*
G01X137801Y484968D02*
X135831Y482998D01*
G01X94554Y421911D02*
X92523Y423942D01*
G01X133864Y481031D02*
X131894Y479061D01*
G01X147642Y439690D02*
X149612Y437720D01*
G01X94414Y445605D02*
X94492D01*
X96452Y447565D01*
X96460D01*
G01X133864Y484968D02*
X131894Y482998D01*
G01X86663Y429536D02*
Y429893D01*
X88586Y431816D01*
G01X82542Y445403D02*
X82541Y445402D01*
X82486D01*
X80712Y443628D01*
G01X100397Y435753D02*
X98427Y433783D01*
G01X86568Y445669D02*
Y445547D01*
X84649Y443628D01*
G01X90426Y449431D02*
X90452D01*
X92523Y451502D01*
G01X90563Y417983D02*
X88648Y416068D01*
X88586D01*
G01X82573Y441360D02*
X82979D01*
X84649Y439690D01*
G01X143705D02*
X145675Y437720D01*
G01X98280Y445405D02*
X98400D01*
X100177Y443628D01*
X100397D01*
G01X90426Y441880D02*
Y441530D01*
X88586Y439690D01*
G01X143705Y479061D02*
X145675Y481031D01*
G01X143705Y482998D02*
X145675Y484968D01*
G01X145737Y418077D02*
X145777Y418037D01*
X145857D01*
X147642Y419822D01*
Y420005D01*
G01X139768Y431816D02*
X141738Y429846D01*
G01X86663Y453583D02*
Y453425D01*
X88586Y451502D01*
G01X82732Y453139D02*
X84369Y451502D01*
X84649D01*
G01X147642Y427879D02*
X149612Y425909D01*
G01X82535Y461227D02*
X82798D01*
X84649Y459376D01*
G01X83021Y473118D02*
X82643D01*
X80712Y471187D01*
G01X141595Y421932D02*
X141778D01*
X143705Y420005D01*
G01X141775Y426153D02*
Y425872D01*
X143705Y423942D01*
G01X86735Y461382D02*
Y461227D01*
X88586Y459376D01*
G01X141763Y437883D02*
X139956Y439690D01*
X139768D01*
G01X86937Y477160D02*
X86249Y476472D01*
Y472787D01*
X84649Y471187D01*
G01X141682Y417902D02*
X141701Y417883D01*
X141890D01*
X143705Y416068D01*
G01X82759Y469436D02*
X84649Y467546D01*
Y467250D01*
G01X145663Y445583D02*
Y445586D01*
X147642Y447565D01*
G01X143705Y431816D02*
X145675Y429846D01*
G01X78421Y473078D02*
X78663Y472836D01*
Y470690D01*
X80712Y468641D01*
Y467250D01*
G01X142008Y457429D02*
X145695D01*
X147642Y459376D01*
G01X141863Y445583D02*
X143705Y447425D01*
Y447565D01*
G01X86959Y469276D02*
X86960Y469275D01*
Y468876D01*
X88586Y467250D01*
G01X137570Y421843D02*
X139669Y423942D01*
X139768D01*
G01X145561Y421879D02*
X145579D01*
X147642Y423942D01*
G01X90965Y465270D02*
X89008Y463313D01*
X88586D01*
G01X129927Y481031D02*
X127957Y479061D01*
G01X129927Y484968D02*
X127957Y482998D01*
G01X110238Y481031D02*
X112208Y479061D01*
G01X110238Y484968D02*
X112208Y482998D01*
G01X94490Y481031D02*
X96460Y479061D01*
G01X86663Y457283D02*
X86742D01*
X88586Y455439D01*
G01X94490Y484968D02*
X96460Y482998D01*
G01X86765Y465205D02*
X84873Y463313D01*
X84649D01*
G01X138061Y418151D02*
Y418298D01*
X139768Y420005D01*
G01X143705Y435753D02*
X145675Y433783D01*
G01X82763Y417750D02*
Y418119D01*
X84649Y420005D01*
G01X86523Y417943D02*
X86463Y417883D01*
Y417882D01*
X84649Y416068D01*
G01X94844Y469182D02*
X94563Y468901D01*
Y457479D01*
X92523Y455439D01*
G01X102469Y469134D02*
X102441Y469106D01*
Y466486D01*
X101138Y465183D01*
X100004D01*
X98134Y463313D01*
X96460D01*
G01X106149Y457371D02*
X104003D01*
X101997Y455365D01*
Y453102D01*
X100397Y451502D01*
G01X79134Y461339D02*
X79195Y461278D01*
Y460893D01*
X80712Y459376D01*
G01X141649Y453189D02*
Y453385D01*
X143703Y455439D01*
X143705D01*
G01X149620Y485149D02*
Y484976D01*
X147642Y482998D01*
G01X81117Y529310D02*
Y534372D01*
G02X81620Y535586I1717J0D01*
G01X81989Y535955D01*
G02X84046Y536807I2057J-2057D01*
G01X91939D01*
G03X97160Y538969I0J7385D01*
G01X112528Y554337D01*
G03X114661Y559489I-5152J5151D01*
G01Y599268D01*
G03X112817Y603723I-6300J1D01*
G01X106284Y610256D01*
G03X101829Y612100I-4454J-4456D01*
G01X90931D01*
G02X89854Y612546I0J1523D01*
G03X88777Y612992I-1077J-1077D01*
G01X85000D01*
G01X103330Y529515D02*
Y532727D01*
G02X104040Y534441I2424J0D01*
G01X121141Y551541D01*
G03X123103Y556279I-4740J4738D01*
G01Y677026D01*
G03X121259Y681481I-6300J1D01*
G01X109084Y693656D01*
G03X104629Y695500I-4454J-4456D01*
G01X89977D01*
G02X88821Y695979I0J1634D01*
G03X87667Y696457I-1154J-1154D01*
G01X85000D01*
G01X99797Y529396D02*
X101415Y531014D01*
G03X102030Y532499I-1485J1485D01*
G01Y532728D01*
G02X103120Y535361I3725J0D01*
G01X120221Y552461D01*
G03X121803Y556280I-3819J3819D01*
G01Y677026D01*
G03X120339Y680561I-5000J0D01*
G01X108164Y692736D01*
G03X104629Y694200I-3535J-3536D01*
G01X101017D01*
X100577Y693760D01*
X99437D01*
X98997Y694200D01*
X97797D01*
X97357Y693760D01*
X96157D01*
X95717Y694200D01*
X94517D01*
X94077Y693760D01*
X92892D01*
X92452Y694200D01*
X89531D01*
G03X88453Y693754I0J-1526D01*
G01X88336Y693637D01*
G02X87541Y693307I-796J794D01*
G01X85000D01*
G01X147678Y529618D02*
X147459Y529838D01*
G02X146642Y531809I1971J1972D01*
G01Y715290D01*
G02X154515Y734297I26880J0D01*
G01X203456Y783238D01*
X204209Y783992D01*
G03X209287Y796254I-12263J12261D01*
G01X209288D01*
Y822767D01*
G03X206240Y830126I-10406J1D01*
G01X205569Y830797D01*
G03X199456Y833329I-6113J-6112D01*
G01X180745D01*
G02X179774Y833731I0J1373D01*
G03X178511Y834254I-1263J-1263D01*
G01X175118D01*
G01X144206Y529584D02*
X144572Y529950D01*
G03X145342Y531809I-1859J1859D01*
G01Y536600D01*
X144902Y537040D01*
Y538240D01*
X145342Y538680D01*
Y539880D01*
X144902Y540320D01*
Y541520D01*
X145342Y541960D01*
Y543160D01*
X144902Y543600D01*
Y544800D01*
X145342Y545240D01*
Y546440D01*
X144902Y546880D01*
Y548080D01*
X145342Y548520D01*
Y601800D01*
X144902Y602240D01*
Y603440D01*
X145342Y603880D01*
Y605080D01*
X144902Y605520D01*
Y606720D01*
X145342Y607160D01*
Y715291D01*
G02X153595Y735216I28180J-1D01*
G01X202536Y784157D01*
X203289Y784911D01*
G03X207988Y796254I-11343J11344D01*
G01Y822767D01*
G03X205321Y829206I-9106J0D01*
G01X204649Y829878D01*
G03X199456Y832029I-5193J-5193D01*
G01X180756D01*
G03X179766Y831619I0J-1400D01*
G02X178523Y831104I-1243J1243D01*
G01X175118D01*
G01X125501Y529596D02*
Y536322D01*
G02X126877Y539644I4698J0D01*
G01X127593Y540360D01*
G03X130930Y548419I-8060J8058D01*
G01Y711099D01*
G03X129086Y715554I-6300J1D01*
G01X116333Y728307D01*
G03X111878Y730151I-4454J-4456D01*
G01X90821D01*
G02X89674Y730626I0J1622D01*
G03X88525Y731102I-1149J-1149D01*
G01X85000D01*
G01X122044Y529612D02*
X123726Y531294D01*
G03X124201Y532441I-1147J1147D01*
G01Y536322D01*
G02X125959Y540566I6002J0D01*
G01X126673Y541280D01*
G03X129630Y548419I-7139J7139D01*
G01Y711099D01*
G03X128166Y714634I-5000J0D01*
G01X115413Y727387D01*
G03X111878Y728851I-3535J-3536D01*
G01X100045D01*
X99605Y728411D01*
X98420D01*
X97980Y728851D01*
X96828D01*
X96388Y728411D01*
X95140D01*
X94700Y728851D01*
X90286D01*
G03X89202Y728402I0J-1533D01*
G02X88118Y727953I-1084J1084D01*
G01X85000D01*
G01X114546Y525502D02*
Y534076D01*
G02X116334Y538393I6105J0D01*
G01X123593Y545651D01*
G03X127150Y554241I-8591J8589D01*
G01Y699979D01*
G03X125306Y704434I-6300J1D01*
G01X110784Y718956D01*
G03X106329Y720800I-4454J-4456D01*
G01X89604D01*
G02X88573Y721227I0J1458D01*
G03X87542Y721654I-1031J-1031D01*
G01X85000D01*
G01X110786Y525501D02*
X112615Y527330D01*
G03X113246Y528853I-1523J1523D01*
G01Y534075D01*
G02X115414Y539313I7406J3D01*
G01X122673Y546571D01*
G03X125850Y554241I-7670J7670D01*
G01Y699979D01*
G03X124386Y703514I-5000J0D01*
G01X109864Y718036D01*
G03X106329Y719500I-3535J-3536D01*
G01X103700D01*
X103200Y719000D01*
X102200D01*
X101700Y719500D01*
X100645D01*
X100205Y719060D01*
X99020D01*
X98580Y719500D01*
X97428D01*
X96988Y719060D01*
X95740D01*
X95300Y719500D01*
X89704D01*
G03X88502Y719002I0J-1700D01*
G02X87300Y718504I-1202J1202D01*
G01X85000D01*
G01X110657Y517857D02*
Y516082D01*
G03X111063Y515102I1386J0D01*
G01X111291Y514874D01*
G03X111786Y514669I495J495D01*
G01X112709D01*
G02X113180Y514474I0J-666D01*
G02X113375Y514003I-471J-471D01*
G01Y513205D01*
G03X115055Y509149I5736J0D01*
G01X117199Y507005D01*
G02X120662Y498645I-8360J-8360D01*
G01Y495678D01*
G02X120457Y495183I-700J0D01*
G01X120083Y494809D01*
G01X110786Y522001D02*
X112005Y520782D01*
G02X112647Y519232I-1550J-1550D01*
G01Y518557D01*
G02X111947Y517857I-700J0D01*
G01X110657D01*
G01X125750Y522071D02*
X125717Y522038D01*
Y494969D01*
G02X124020Y490872I-5794J0D01*
G01X125501Y526096D02*
Y522320D01*
X125750Y522071D01*
G01X121801Y522079D02*
X121673Y521951D01*
G03X121468Y521456I495J-495D01*
G01Y520100D01*
G03X122168Y519400I700J0D01*
G01X123606D01*
G02X124035Y519223I1J-606D01*
G01X124212Y519045D01*
G02X124417Y518550I-495J-495D01*
G01Y495767D01*
G02X124391Y495505I-1355J2D01*
G02X124020Y494809I-1329J262D01*
G01X122044Y526112D02*
Y526111D01*
X123672Y524483D01*
G02X123877Y523988I-495J-495D01*
G01Y522935D01*
G02X123672Y522440I-700J0D01*
G01X123516Y522284D01*
G02X123021Y522079I-495J495D01*
G01X121801D01*
G01X181054Y517848D02*
X178093Y514886D01*
G02X176032Y514033I-2060J2061D01*
G01X175679D01*
G03X174839Y513685I0J-1188D01*
G01X174558Y513404D01*
X174559D01*
X172333Y511178D01*
G02X164664Y508003I-7667J7669D01*
G01X159963D01*
G03X156403Y506529I-1J-5034D01*
G01X156060Y506185D01*
X154994Y505119D01*
Y505114D01*
X146039Y496159D01*
G03X145469Y494783I1376J-1376D01*
G02X143951Y491118I-5183J0D01*
G01X143705Y490872D01*
G01X177099Y517848D02*
Y516192D01*
G02X176240Y515333I-859J0D01*
G01X175679D01*
G03X173919Y514605I-1J-2488D01*
G01X171419Y512104D01*
X171420D01*
X171413Y512098D01*
G02X164665Y509303I-6748J6748D01*
G01X159964D01*
G03X155483Y507448I-2J-6334D01*
G01X155140Y507104D01*
X153694Y505658D01*
Y505653D01*
X144157Y496116D01*
G03X143705Y495025I1091J-1091D01*
G01Y494809D01*
G01X114675Y517858D02*
Y513204D01*
G03X115975Y510069I4435J2D01*
G01X118119Y507925D01*
G02X120595Y504478I-9280J-9279D01*
G02X121962Y498646I-11756J-5832D01*
G01Y495388D01*
X121942Y495391D01*
X121962Y494683D01*
G02X120596Y491385I-4664J0D01*
G01X120083Y490872D01*
G01X114546Y522002D02*
G02X114675Y521691I-311J-311D01*
G01Y517858D01*
G01X103454Y521857D02*
G02X103764Y521109I-748J-748D01*
G01Y518505D01*
G03X105790Y513614I6917J0D01*
G01X115275Y504129D01*
G02X117770Y498105I-6025J-6024D01*
G01Y495150D01*
X117756Y495136D01*
X117770Y494183D01*
G02X116578Y491305I-4070J0D01*
G01X116145Y490872D01*
G01X103330Y526015D02*
Y521981D01*
X103454Y521857D01*
G01X99435Y521826D02*
Y520671D01*
G03X100063Y520043I628J0D01*
G01X101498D01*
G02X102464Y519077I0J-966D01*
G01Y518505D01*
G03X104870Y512694I8217J-1D01*
G01X114355Y503209D01*
G02X116470Y498104I-5104J-5105D01*
G01Y495689D01*
X116448Y495667D01*
X116454Y495232D01*
G02X116307Y494971I-539J132D01*
G01X116145Y494809D01*
G01X99797Y525896D02*
X101234Y524459D01*
G02X101386Y524231I-495J-495D01*
G01X101408Y524178D01*
G02X101432Y524059I-288J-120D01*
G01Y522709D01*
G02X101227Y522214I-700J0D01*
G01X101044Y522031D01*
G02X100549Y521826I-495J495D01*
G01X99435D01*
G01X81375Y521698D02*
Y515911D01*
G03X82863Y512319I5080J0D01*
G01X84194Y510988D01*
G03X85896Y510283I1702J1702D01*
G01X95175D01*
G02X100172Y508214I1J-7067D01*
G01X108294Y500092D01*
G02X109871Y496283I-3808J-3808D01*
G01Y494735D01*
G02X108271Y490872I-5463J0D01*
G01X81117Y525810D02*
G02X81375Y525187I-623J-623D01*
G01Y521698D01*
G01X136663Y525453D02*
G02X135599Y528022I2569J2569D01*
G01Y707492D01*
G02X147065Y735172I39146J-1D01*
G01X147392Y735500D01*
X201056Y789164D01*
G03X204008Y796291I-7129J7128D01*
G01Y816053D01*
G03X201928Y821075I-7101J1D01*
G01X200600Y822403D01*
G03X197036Y823879I-3563J-3563D01*
G01X180771D01*
G02X179755Y824300I0J1437D01*
G03X178538Y824804I-1217J-1217D01*
G01X175118D01*
G01X133163Y525553D02*
X133338Y525728D01*
G03X134299Y528048I-2320J2320D01*
G01Y535400D01*
X133859Y535840D01*
Y537040D01*
X134299Y537480D01*
Y538680D01*
X133859Y539120D01*
Y540320D01*
X134299Y540760D01*
Y541960D01*
X133859Y542400D01*
Y543600D01*
X134299Y544040D01*
Y545240D01*
X133859Y545680D01*
Y546880D01*
X134299Y547320D01*
Y548520D01*
X133859Y548960D01*
Y550160D01*
X134299Y550600D01*
Y707492D01*
X134300D01*
G02X146145Y736091I40445J1D01*
G01X146471Y736418D01*
X200136Y790083D01*
G03X202708Y796292I-6209J6209D01*
G01Y816053D01*
G03X201009Y820155I-5801J0D01*
G01X199680Y821484D01*
G03X197036Y822579I-2644J-2644D01*
G01X180869D01*
G03X179686Y822089I0J-1673D01*
G02X178636Y821654I-1050J1050D01*
G01X175118D01*
G01X170037Y522020D02*
Y517744D01*
G02X168623Y514330I-4828J0D01*
G01X167945Y513652D01*
G02X161547Y511003I-6397J6399D01*
G01X160554D01*
G03X154011Y508293I0J-9253D01*
G01X142012Y496294D01*
G03X141463Y494969I1325J-1325D01*
G01Y494964D01*
G02X141442Y494471I-5787J0D01*
G02X139768Y490872I-5766J493D01*
G01X165955Y522020D02*
G03X165763Y521556I465J-464D01*
G01Y520037D01*
G03X166463Y519337I700J0D01*
G01X167283D01*
G02X168363Y518889I-1J-1528D01*
G01X168528Y518725D01*
G02X168666Y518113I-1289J-612D01*
G01Y517019D01*
G02X168659Y516861I-1946J7D01*
G02X168096Y515643I-1939J157D01*
G01X167025Y514572D01*
G02X161547Y512303I-5478J5478D01*
G01X160554D01*
G03X153091Y509212I-1J-10553D01*
G01X140665Y496786D01*
X140532Y496652D01*
G03X139768Y494809I1843J-1844D01*
G01X158917Y517830D02*
G03X157408Y517205I0J-2134D01*
G01X155025Y514822D01*
X154842Y514638D01*
X137946Y497742D01*
G03X137465Y496581I1161J-1161D01*
G01Y494462D01*
G02X136082Y491123I-4722J0D01*
G01X135831Y490872D01*
G01X136913Y517903D02*
Y514328D01*
G02X136296Y512838I-2107J0D01*
G01X133113Y509655D01*
X132394Y508935D01*
G03X132393Y508934I6109J-6110D01*
G03X129863Y502826I6110J-6109D01*
G01Y494783D01*
G02X128445Y491361I-4840J1D01*
G01X127957Y490872D01*
G01X136663Y521953D02*
Y518507D01*
G03X136913Y517903I854J0D01*
G01X132913D02*
Y516657D01*
G03X133093Y516221I616J-1D01*
G01X133440Y515874D01*
G03X134007Y515639I567J567D01*
G01X134803D01*
G02X135071Y515586I1J-700D01*
G02X135235Y515450I-141J-337D01*
G02X135620Y514354I-948J-949D01*
G01X135607Y514239D01*
G02X135376Y513758I-801J89D01*
G01X135061Y513443D01*
Y513442D01*
X132193Y510574D01*
X131474Y509854D01*
G03X128563Y502827I7029J-7028D01*
G01Y496272D01*
G02X127957Y494809I-2069J0D01*
G01X133163Y522053D02*
X134925Y520290D01*
G02X135130Y519795I-495J-495D01*
G01Y518603D01*
G02X134430Y517903I-700J0D01*
G01X132913D01*
G01X192113Y522003D02*
G03X191014Y519350I2653J-2653D01*
G01Y517263D01*
G02X190028Y514881I-3367J-1D01*
G01X189494Y514348D01*
X189025Y513878D01*
X187519Y512372D01*
G02X183148Y510563I-4369J4371D01*
G01X181512D01*
G03X178150Y509171I-1J-4754D01*
G01X177516Y508536D01*
X176158Y507177D01*
G02X169216Y504302I-6942J6944D01*
G01X166546D01*
X166545Y504303D01*
X160165D01*
G03X157294Y503115I0J-4062D01*
G01X157165Y502984D01*
X151016Y496835D01*
Y496830D01*
X149665Y495479D01*
G03X149223Y494412I1067J-1067D01*
G01Y494056D01*
G02X147820Y491050I-4836J427D01*
G01X147642Y490872D01*
G01X188113Y522003D02*
X188918Y521198D01*
G02X189714Y519276I-1922J-1922D01*
G01Y517263D01*
G02X189109Y515801I-2067J-1D01*
G01X188575Y515268D01*
X186599Y513292D01*
G02X183149Y511863I-3450J3450D01*
G01X181512D01*
G03X177230Y510090I-1J-6054D01*
G01X176596Y509455D01*
X175238Y508097D01*
G02X169215Y505602I-6023J6023D01*
G01X167085D01*
X167084Y505603D01*
X160165D01*
G03X156373Y504033I-1J-5362D01*
G01X156243Y503902D01*
X147987Y495646D01*
G03X147642Y494813I833J-833D01*
G01Y494809D01*
G01X92158Y525184D02*
Y528120D01*
G02X92588Y529158I1468J0D01*
G01X117822Y554391D01*
G03X119377Y558148I-3758J3756D01*
G01Y666052D01*
G03X117533Y670507I-6300J1D01*
G01X103784Y684256D01*
G03X99329Y686100I-4454J-4456D01*
G01X89942D01*
G02X88846Y686554I0J1550D01*
G03X87750Y687008I-1096J-1096D01*
G01X85000D01*
G01X88606Y525183D02*
X90226Y526803D01*
X90497Y527075D01*
G03X90857Y527909I-870J870D01*
G03X90858Y527945I-1229J52D01*
G01Y528121D01*
G02X91668Y530078I2769J0D01*
G01X116902Y555311D01*
G03X118077Y558148I-2837J2837D01*
G01Y666052D01*
G03X116613Y669587I-5000J0D01*
G01X110521Y675679D01*
X109899D01*
X109093Y676485D01*
Y677107D01*
X108244Y677956D01*
X107622D01*
X106774Y678804D01*
Y679427D01*
X105925Y680275D01*
X105303D01*
X104465Y681113D01*
Y681735D01*
X102864Y683336D01*
G03X99329Y684800I-3535J-3536D01*
G01X90066D01*
G03X88929Y684329I0J-1608D01*
G02X87792Y683858I-1137J1137D01*
G01X85000D01*
G01X154924Y517879D02*
Y517841D01*
G02X154018Y515654I-3093J0D01*
G01X137026Y498662D01*
G03X136165Y496582I2082J-2080D01*
G01Y495615D01*
G02X135831Y494809I-1140J0D01*
G01X92400Y517603D02*
Y515738D01*
G03X92775Y514427I2482J1D01*
G03X93847Y513983I1072J1072D01*
G01X96336D01*
G02X102082Y511603I0J-8126D01*
G01X112402Y501283D01*
G02X113863Y497756I-3527J-3527D01*
G01Y494683D01*
G02X112338Y491003I-5205J1D01*
G01X112208Y490872D01*
G01X92158Y521684D02*
G02X92400Y521100I-584J-584D01*
G01Y517603D01*
G01X88412D02*
Y516320D01*
G03X88744Y515725I699J0D01*
G01X88910Y515600D01*
G03X89331Y515460I420J560D01*
G01X90470D01*
G02X91026Y515186I1J-700D01*
G01X91173Y514994D01*
G03X91748Y513621I3708J746D01*
G03X91855Y513507I2106J1870D01*
G03X93847Y512683I1991J1992D01*
G01X96336D01*
G02X101162Y510684I0J-6826D01*
G01X106257Y505589D01*
X107512Y504333D01*
Y504334D01*
X111482Y500363D01*
G02X112563Y497755I-2606J-2608D01*
G01Y495666D01*
G02X112488Y495247I-1212J1D01*
G02X112479Y495224I-1133J430D01*
G02X112208Y494809I-1129J441D01*
G01X88606Y521683D02*
X90153Y520136D01*
G02X90358Y519641I-495J-495D01*
G01Y518303D01*
G02X89658Y517603I-700J0D01*
G01X88412D01*
G01X147904Y522037D02*
X147814Y521947D01*
Y517976D01*
G02X147148Y516368I-2274J0D01*
G01X135821Y505041D01*
G03X133519Y499483I5559J-5558D01*
G01Y494795D01*
G02X131894Y490872I-5548J0D01*
G01X147678Y526118D02*
Y522263D01*
X147904Y522037D01*
G01X143962Y522038D02*
G03X143757Y521543I495J-495D01*
G01Y520036D01*
G03X144457Y519336I700J0D01*
G01X145813D01*
G02X146328Y519109I0J-698D01*
G01X146396Y519041D01*
G02X146514Y518756I-285J-285D01*
G01Y518014D01*
G02X146508Y517885I-1400J0D01*
G02X146228Y517288I-969J90D01*
G01X134901Y505961D01*
G03X132219Y499484I6480J-6477D01*
G01Y495594D01*
G02X131894Y494809I-1110J0D01*
G01X144206Y526084D02*
X145688Y524602D01*
Y522738D01*
G02X144988Y522038I-700J0D01*
G01X143962D01*
G01X91198Y595087D02*
X90205Y594094D01*
X85001D01*
X85000Y594095D01*
G01X91123Y591887D02*
X90180Y590944D01*
X85001D01*
X85000Y590945D01*
G01X91223Y588487D02*
X90531Y587795D01*
X85001D01*
X85000Y587796D01*
G01X90878Y585185D02*
X90338Y584645D01*
X85001D01*
X85000Y584646D01*
G01X80326Y659038D02*
X85648D01*
X85654Y659044D01*
G01X79922Y632636D02*
X83960D01*
G01X80191Y651337D02*
Y655403D01*
X80326Y655538D01*
G01X83500Y653600D02*
X81562Y655538D01*
X80326D01*
G01X79967Y640044D02*
X79922Y639999D01*
Y636136D01*
G01X79967Y640044D02*
X83500D01*
G01X80653Y747654D02*
X84654D01*
X84900Y747900D01*
G01X90746Y712435D02*
X90515Y712204D01*
X85001D01*
X85000Y712205D01*
G01X90947Y709040D02*
X90933Y709054D01*
X85001D01*
X85000Y709055D01*
G01X91003Y705214D02*
X90312Y705905D01*
X85001D01*
X85000Y705906D01*
G01X91130Y701741D02*
X90116Y702755D01*
X85001D01*
X85000Y702756D01*
G01X85300Y755100D02*
X85203Y755197D01*
X80653D01*
G01D02*
Y751154D01*
G01X80415Y776383D02*
X84517D01*
X85000Y775900D01*
G01X80464Y768256D02*
Y772834D01*
X80415Y772883D01*
G01D02*
X80517D01*
X84100Y769300D01*
Y769000D01*
G01X203240Y102533D02*
Y104347D01*
X201237Y106350D01*
G01X216447Y88039D02*
X213481D01*
X211347Y90173D01*
Y91213D01*
X209660Y92900D01*
Y94868D01*
X206475Y98053D01*
G01D02*
X206740Y98318D01*
Y102533D01*
G01D02*
Y104547D01*
X204849Y106438D01*
G01X170302Y147100D02*
Y151107D01*
G01X168353Y143740D02*
Y145151D01*
X170302Y147100D01*
G01X219504Y181620D02*
X215700D01*
G01X163979Y141189D02*
X163811Y141357D01*
Y145062D01*
G01D02*
X163915Y145166D01*
Y148352D01*
X164396Y148833D01*
Y151107D01*
G01X160359Y160066D02*
X157330D01*
X152732Y164664D01*
G01D02*
Y165149D01*
X149031Y168850D01*
G01X173940Y237502D02*
X163988D01*
X161108Y240382D01*
Y241083D01*
X157763Y244428D01*
G01X168324Y246397D02*
X168163D01*
X164222Y250338D01*
X157763D01*
G01X187601Y275296D02*
X186661Y274356D01*
X172490D01*
X170898Y275948D01*
X157763D01*
G01X196215Y274233D02*
X194754D01*
X190472Y269951D01*
X184317D01*
X183913Y269547D01*
X171699D01*
X169238Y272008D01*
X157763D01*
G01X175400Y246422D02*
X170845D01*
X164959Y252308D01*
X157763D01*
G01X200015Y250333D02*
X198794D01*
X197099Y252028D01*
X186392D01*
X183172Y248808D01*
X170722D01*
X165252Y254278D01*
X157763D01*
G01X175527Y251228D02*
X170565D01*
X165545Y256248D01*
X157763D01*
G01X192615Y254537D02*
X191785Y253707D01*
X170349D01*
X165838Y258218D01*
X157763D01*
G01X175659Y256562D02*
X172525D01*
X172508Y256545D01*
X169774D01*
X166131Y260188D01*
X157763D01*
G01X188615Y262433D02*
X188539D01*
X185115Y259009D01*
X173644D01*
X172508Y260145D01*
X171438D01*
X169425Y262158D01*
X157763D01*
G01X177306Y261409D02*
X173507D01*
X173171Y261745D01*
X172101D01*
X169718Y264128D01*
X157763D01*
G01X196015Y265433D02*
X186096D01*
X184515Y263852D01*
X182658D01*
X182615Y263809D01*
X172300D01*
X170011Y266098D01*
X157763D01*
G01X176293Y267018D02*
X171702D01*
X168652Y270068D01*
X167042D01*
X167012Y270038D01*
X157763D01*
G01X176432Y271928D02*
X172218D01*
X170168Y273978D01*
X157763D01*
G01X167760Y239626D02*
X160988Y246398D01*
X157763D01*
G01X173940Y241702D02*
X169836D01*
X167760Y239626D01*
G01X176460Y285561D02*
X174727Y283828D01*
X157763D01*
G01X158445Y331698D02*
Y335664D01*
X158631Y335850D01*
G01X154845Y331798D02*
Y335571D01*
X154602Y335814D01*
G01X780514Y397660D02*
X773071D01*
G02X771482Y398318I0J2248D01*
G03X769892Y398977I-1590J-1589D01*
G01X704800D01*
G03X702438Y397998I1J-3341D01*
G01X701069Y396630D01*
X624849Y320410D01*
G02X621100Y318857I-3749J3749D01*
G01X163207D01*
G02X159105Y320555I-1J5801D01*
G01X157425Y322235D01*
G02X155800Y326054I3924J3925D01*
G01X155799D01*
G03X154845Y328298I-3260J-61D01*
G01X158445Y328198D02*
X157998Y327751D01*
X157100Y326160D01*
G03X158345Y323155I4253J2D01*
G01X160025Y321475D01*
G03X163207Y320157I3182J3182D01*
G01X510940D01*
X511380Y320597D01*
X512580D01*
X513020Y320157D01*
X514220D01*
X514660Y320597D01*
X515860D01*
X516300Y320157D01*
X566300D01*
X566740Y320597D01*
X567940D01*
X568380Y320157D01*
X569580D01*
X570020Y320597D01*
X571220D01*
X571660Y320157D01*
X572860D01*
X573300Y320597D01*
X574500D01*
X574940Y320157D01*
X576140D01*
X576580Y320597D01*
X577780D01*
X578220Y320157D01*
X579420D01*
X579860Y320597D01*
X581060D01*
X581500Y320157D01*
X621100D01*
G03X623928Y321329I-1J4000D01*
G01X623929D01*
X630207Y327607D01*
Y328230D01*
X631056Y329078D01*
X631678D01*
X632526Y329927D01*
Y330549D01*
X633375Y331397D01*
X633997D01*
X634846Y332246D01*
Y332868D01*
X635694Y333717D01*
X636317D01*
X637165Y334565D01*
Y335187D01*
X638014Y336036D01*
X638636D01*
X639484Y336884D01*
Y337507D01*
X640333Y338355D01*
X640955D01*
X677310Y374710D01*
Y375332D01*
X678159Y376181D01*
X678781D01*
X679630Y377029D01*
Y377652D01*
X680478Y378500D01*
X681100D01*
X681949Y379349D01*
Y379971D01*
X682797Y380819D01*
X683420D01*
X684268Y381668D01*
Y382290D01*
X685117Y383139D01*
X685739D01*
X686500Y383900D01*
Y384700D01*
X687250Y385450D01*
X688050D01*
X701517Y398917D01*
G02X704800Y400277I3283J-3283D01*
G01X769945D01*
G03X771536Y400936I0J2250D01*
G02X773127Y401595I1591J-1591D01*
G01X780514D01*
G01X176560Y294061D02*
X172643D01*
X170315Y291733D01*
G01X148834Y284832D02*
Y284868D01*
X153704Y289738D01*
X157763D01*
G01D02*
X168320D01*
X170315Y291733D01*
G01X193115Y282033D02*
X192441D01*
X189469Y279061D01*
X172485D01*
X171658Y279888D01*
X157763D01*
G01X176393Y276656D02*
X172490D01*
X171228Y277918D01*
X157763D01*
G01X176360Y281361D02*
X175863Y281858D01*
X157763D01*
G01X165885Y332263D02*
X166806Y331342D01*
G02X167000Y330874I-467J-468D01*
G01Y328536D01*
G03X168112Y325848I3802J-1D01*
G01X169568Y324392D01*
G03X172256Y323280I2687J2690D01*
G01X618700D01*
G03X622137Y324703I1J4860D01*
G01Y324704D01*
X710616Y413183D01*
X711351Y413917D01*
G02X713300Y414725I1950J-1949D01*
G01X769942D01*
G02X771534Y414065I0J-2250D01*
G01X771535D01*
G03X773128Y413405I1593J1592D01*
G01X780514D01*
G01X169385Y332263D02*
X168709Y331586D01*
G03X168300Y330600I986J-987D01*
G01Y328536D01*
G03X169032Y326768I2501J0D01*
G01X170488Y325312D01*
G03X172256Y324580I1768J1769D01*
G01X509176D01*
X509616Y325020D01*
X510816D01*
X511256Y324580D01*
X512456D01*
X512896Y325020D01*
X514096D01*
X514536Y324580D01*
X515736D01*
X516176Y325020D01*
X517376D01*
X517816Y324580D01*
X519016D01*
X519456Y325020D01*
X520656D01*
X521096Y324580D01*
X571096D01*
X571536Y325020D01*
X572736D01*
X573176Y324580D01*
X574376D01*
X574816Y325020D01*
X576016D01*
X576456Y324580D01*
X577656D01*
X578096Y325020D01*
X579296D01*
X579736Y324580D01*
X580936D01*
X581376Y325020D01*
X582576D01*
X583016Y324580D01*
X618700D01*
G03X621217Y325622I1J3559D01*
G01Y325623D01*
X632009Y336415D01*
Y337038D01*
X632858Y337886D01*
X633480D01*
X634329Y338735D01*
Y339357D01*
X635177Y340206D01*
X635800D01*
X636648Y341054D01*
Y341676D01*
X637497Y342525D01*
X638119D01*
X638967Y343373D01*
Y343996D01*
X639816Y344844D01*
X640438D01*
X678558Y382964D01*
Y383586D01*
X679406Y384435D01*
X680029D01*
X680877Y385283D01*
Y385906D01*
X681726Y386754D01*
X682348D01*
X683197Y387603D01*
Y388225D01*
X684045Y389074D01*
X684667D01*
X685516Y389922D01*
Y390544D01*
X686364Y391393D01*
X686987D01*
X687835Y392241D01*
Y392864D01*
X688684Y393712D01*
X689306D01*
X710431Y414837D01*
G02X713299Y416025I2869J-2869D01*
G01X770482D01*
G03X771537Y416462I0J1492D01*
G01X772037Y416962D01*
G02X772962Y417345I925J-925D01*
G01X780514D01*
G01X188047Y340699D02*
X188896Y339851D01*
G02X189300Y338874I-977J-976D01*
G01X189323Y338851D01*
Y337813D01*
G03X190435Y335125I3802J-1D01*
G01X192548Y333012D01*
G03X195236Y331900I2687J2690D01*
G01X611000D01*
G03X613798Y333059I0J3957D01*
G01X717919Y437180D01*
G02X720381Y438200I2462J-2462D01*
G01X757758D01*
G03X761858Y439898I-1J5801D01*
G01X767244Y445284D01*
G02X769506Y446222I2263J-2262D01*
G01X771047D01*
G02X772637Y445563I0J-2248D01*
G03X774226Y444905I1589J1590D01*
G01X780514D01*
G01X180438Y336503D02*
X180394Y336460D01*
G03X179500Y334300I2160J-2159D01*
G01Y331873D01*
G03X180400Y329700I3073J0D01*
G03X182573Y328800I2173J2173D01*
G01X500540D01*
X500980Y329240D01*
X502180D01*
X502620Y328800D01*
X503820D01*
X504260Y329240D01*
X505460D01*
X505900Y328800D01*
X555900D01*
X556340Y329240D01*
X557540D01*
X557980Y328800D01*
X559180D01*
X559620Y329240D01*
X560820D01*
X561260Y328800D01*
X562460D01*
X562900Y329240D01*
X564100D01*
X564540Y328800D01*
X565740D01*
X566180Y329240D01*
X567380D01*
X567820Y328800D01*
X569020D01*
X569460Y329240D01*
X570660D01*
X571100Y328800D01*
X614500D01*
G03X616772Y329741I0J3213D01*
G01X620276Y333245D01*
Y333867D01*
X621125Y334716D01*
X621747D01*
X622595Y335564D01*
Y336187D01*
X623444Y337035D01*
X624066D01*
X624915Y337884D01*
Y338506D01*
X625763Y339354D01*
X626385D01*
X627234Y340203D01*
Y340825D01*
X628082Y341674D01*
X628705D01*
X629553Y342522D01*
Y343145D01*
X630402Y343993D01*
X631024D01*
X667354Y380323D01*
Y380945D01*
X668203Y381794D01*
X668825D01*
X669674Y382642D01*
Y383264D01*
X670522Y384113D01*
X671144D01*
X671993Y384961D01*
Y385584D01*
X672842Y386432D01*
X673464D01*
X674312Y387281D01*
Y387903D01*
X675161Y388752D01*
X675783D01*
X676565Y389534D01*
Y390365D01*
X677200Y391000D01*
X678031D01*
X716065Y429034D01*
X717214Y430182D01*
X717391Y430360D01*
G02X720800Y431772I3408J-3406D01*
G01X770040D01*
G03X771631Y432431I0J2250D01*
G02X773222Y433090I1591J-1591D01*
G01X780514D01*
G01X191557Y340639D02*
G03X190623Y338716I2310J-2310D01*
G01Y337813D01*
G03X191355Y336045I2501J0D01*
G01X193468Y333932D01*
G03X195236Y333200I1768J1769D01*
G01X381560D01*
X382000Y333640D01*
X383200D01*
X383640Y333200D01*
X384840D01*
X385280Y333640D01*
X386480D01*
X386920Y333200D01*
X436920D01*
X437360Y333640D01*
X438560D01*
X439000Y333200D01*
X440200D01*
X440640Y333640D01*
X441840D01*
X442280Y333200D01*
X443480D01*
X443920Y333640D01*
X445120D01*
X445560Y333200D01*
X446760D01*
X447200Y333640D01*
X448400D01*
X448840Y333200D01*
X498840D01*
X499280Y333640D01*
X500480D01*
X500920Y333200D01*
X502120D01*
X502560Y333640D01*
X503760D01*
X504200Y333200D01*
X505400D01*
X505840Y333640D01*
X507040D01*
X507480Y333200D01*
X508680D01*
X509120Y333640D01*
X510320D01*
X510760Y333200D01*
X560760D01*
X561200Y333640D01*
X562400D01*
X562840Y333200D01*
X564040D01*
X564480Y333640D01*
X565680D01*
X566120Y333200D01*
X567320D01*
X567760Y333640D01*
X568960D01*
X569400Y333200D01*
X570600D01*
X571040Y333640D01*
X572240D01*
X572680Y333200D01*
X611000D01*
G03X612878Y333978I0J2656D01*
G01X620905Y342005D01*
Y342628D01*
X621753Y343476D01*
X622376D01*
X623224Y344325D01*
Y344947D01*
X624073Y345795D01*
X624695D01*
X625544Y346644D01*
Y347266D01*
X626392Y348115D01*
X627014D01*
X627863Y348963D01*
Y349585D01*
X628711Y350434D01*
X629334D01*
X716750Y437850D01*
G02X720733Y439500I3983J-3983D01*
G01X757757D01*
G03X760938Y440818I-1J4500D01*
G01X766324Y446204D01*
G02X769506Y447522I3182J-3182D01*
G01X771090D01*
G03X772681Y448181I0J2250D01*
G02X774272Y448840I1591J-1591D01*
G01X780514D01*
G01X176898Y336463D02*
X177896Y335465D01*
G02X178200Y334731I-734J-734D01*
G01Y331873D01*
G03X179480Y328780I4374J-1D01*
G03X182573Y327500I3092J3094D01*
G01X614500D01*
G03X617694Y328823I0J4517D01*
G01X718135Y429264D01*
X718312Y429442D01*
G02X720800Y430472I2487J-2488D01*
G01X769897D01*
G02X771486Y429814I0J-2248D01*
G03X773077Y429155I1591J1591D01*
G01X780514D01*
G01X172818Y288683D02*
X171903Y287768D01*
X157763D01*
G01X176560Y289861D02*
X173996D01*
X172818Y288683D01*
G01X165885Y335763D02*
Y339663D01*
X165635Y339913D01*
G01X176898Y339963D02*
Y343943D01*
X176688Y344153D01*
G01X169385Y335763D02*
Y339663D01*
X169635Y339913D01*
G01X180438Y340003D02*
Y343903D01*
X180688Y344153D01*
G01X188047Y344199D02*
Y348049D01*
X187807Y348289D01*
G01X191557Y344139D02*
Y348039D01*
X191807Y348289D01*
G01X199138Y344799D02*
X199332Y344605D01*
G02X200300Y342268I-2337J-2337D01*
G01Y340536D01*
G03X201412Y337848I3802J-1D01*
G01X201928Y337332D01*
G03X204616Y336220I2687J2690D01*
G01X550044D01*
G03X552732Y337332I1J3802D01*
G01X663982Y448582D01*
G02X667164Y449900I3182J-3182D01*
G01X672765D01*
G03X675947Y451218I0J4500D01*
G01X676778Y452049D01*
G03X677129Y452471I-2114J2115D01*
G01X677748Y453373D01*
G02X678509Y453773I761J-523D01*
G01X202638Y344799D02*
G03X201600Y342293I2506J-2506D01*
G01Y340536D01*
G03X202332Y338768I2501J0D01*
G01X202848Y338252D01*
G03X204616Y337520I1768J1769D01*
G01X550044D01*
G03X551812Y338252I0J2501D01*
G01X663062Y449502D01*
G02X667164Y451200I4101J-4103D01*
G01X672765D01*
G03X675027Y452138I-1J3200D01*
G01X675858Y452969D01*
G03X676057Y453207I-1192J1198D01*
G01X676056D01*
G03X676353Y454164I-1393J957D01*
G01Y455138D01*
G03X675935Y456147I-1427J0D01*
G01X674109Y457973D01*
G01X210180Y348944D02*
X210237Y348887D01*
G02X211200Y346562I-2325J-2325D01*
G01Y344174D01*
G03X212480Y341080I4374J-2D01*
G03X214849Y340100I2367J2370D01*
G01X508002D01*
G03X528882Y344902I0J47796D01*
G03X541799Y354099I-20881J42996D01*
G01X652300Y464600D01*
X652720Y465021D01*
G02X652955Y465243I3889J-3881D01*
G01X653041Y465319D01*
G02X653075Y465349I4207J-4734D01*
G02X657120Y467258I4625J-4560D01*
G01X657620D01*
G03X660225Y468337I0J3684D01*
G01X661389Y469501D01*
G03X661709Y470273I-771J772D01*
G01X213780Y348944D02*
G03X212500Y345854I3090J-3090D01*
G01Y344173D01*
G03X213400Y342000I3073J0D01*
G03X214849Y341400I1449J1449D01*
G01X430060D01*
X430500Y341840D01*
X431700D01*
X432140Y341400D01*
X433340D01*
X433780Y341840D01*
X434980D01*
X435420Y341400D01*
X436620D01*
X437060Y341840D01*
X438260D01*
X438700Y341400D01*
X439900D01*
X440340Y341840D01*
X441540D01*
X441980Y341400D01*
X491980D01*
X492420Y341840D01*
X493620D01*
X494060Y341400D01*
X495260D01*
X495700Y341840D01*
X496900D01*
X497340Y341400D01*
X498540D01*
X498980Y341840D01*
X500180D01*
X500620Y341400D01*
X501820D01*
X502260Y341840D01*
X503460D01*
X503900Y341400D01*
X508000D01*
G03X528314Y346072I0J46499D01*
G03X540879Y355019I-20314J41826D01*
G01X651800Y465940D01*
G02X652187Y466301I5398J-5399D01*
G02X657004Y468553I5512J-5512D01*
G01X657606D01*
G03X659306Y469257I0J2404D01*
G03X659703Y470214I-957J958D01*
G01Y471400D01*
G03X659081Y472900I-2122J-1D01*
G01X657609Y474373D01*
G01X176751Y387090D02*
X176727D01*
X174114Y384477D01*
X167422D01*
X163390Y388509D01*
G01X157251Y414149D02*
X155516Y415884D01*
Y416068D01*
G01X161477Y394511D02*
X161325D01*
X159453Y396383D01*
G01X177715Y397471D02*
X175709Y399477D01*
X173118D01*
X171264Y397623D01*
Y396383D01*
G01Y400320D02*
X179349D01*
X180991Y398678D01*
G01D02*
X183091Y400778D01*
X191160D01*
X193115Y402733D01*
X206315D01*
X210010Y399038D01*
X214870D01*
X214871Y399037D01*
X218857D01*
X219807Y399987D01*
Y403211D01*
X221898Y405302D01*
X224403D01*
G01X212500Y395500D02*
X212377Y395377D01*
X205751D01*
X204404Y396724D01*
X202416D01*
X201069Y395377D01*
X198189D01*
X197917Y395649D01*
X190341D01*
X190205Y395785D01*
X184125D01*
X179731Y391391D01*
Y387665D01*
X175743Y383677D01*
X160348D01*
X155516Y388509D01*
G01X180809Y414170D02*
X173233Y406594D01*
X168927D01*
X167327Y408194D01*
G01X217800Y395900D02*
X216269Y397431D01*
X213970D01*
Y397435D01*
X213967Y397438D01*
X209156D01*
X205961Y400633D01*
X200315D01*
G01X171264Y392446D02*
X175784D01*
X180316Y396978D01*
X181696D01*
X183703Y398985D01*
X196367D01*
X198015Y400633D01*
X200315D01*
G01X171264Y408194D02*
X173701Y410631D01*
X174739D01*
X179804Y415696D01*
Y416304D01*
X181300Y417800D01*
G01X149362Y413951D02*
X151291Y415880D01*
X151391D01*
X151579Y416068D01*
G01X149498Y406396D02*
X149781D01*
X151579Y408194D01*
G01X153587Y406496D02*
X153817D01*
X155515Y408194D01*
X155516D01*
G01X157554Y402251D02*
X155548Y404257D01*
X155516D01*
G01X157698Y406313D02*
X159453Y408068D01*
Y408194D01*
G01X161475Y410299D02*
X161391Y410383D01*
X161201D01*
X159453Y412131D01*
G01X206871Y397177D02*
X206214D01*
X205067Y398324D01*
X201753D01*
X200678Y397249D01*
X191004D01*
X190868Y397385D01*
X184022D01*
X182115Y395478D01*
X181080D01*
X174130Y388528D01*
X172720D01*
X172402Y388846D01*
X169771D01*
X168408Y390209D01*
X167159D01*
X165090Y392278D01*
Y394683D01*
X163390Y396383D01*
G01X165266Y409882D02*
X165078D01*
X163390Y408194D01*
G01X165337Y414489D02*
X163445Y412597D01*
Y412186D01*
X163390Y412131D01*
G01X176662Y418122D02*
X175704D01*
X172050Y414468D01*
X169664D01*
X167327Y412131D01*
G01X153528Y410052D02*
X155516Y412040D01*
Y412131D01*
G01X165455Y398256D02*
X165454D01*
X163390Y400320D01*
G01X165229Y402019D02*
X165139Y402109D01*
Y402508D01*
X163390Y404257D01*
G01X173864Y397677D02*
X172979Y396792D01*
Y395693D01*
X171969Y394683D01*
X169027D01*
X167327Y396383D01*
G01X199138Y348299D02*
Y352199D01*
X198888Y352449D01*
G01X202638Y348299D02*
Y352199D01*
X202888Y352449D01*
G01X210180Y352444D02*
Y356344D01*
X209930Y356594D01*
G01X213780Y352444D02*
Y356344D01*
X214030Y356594D01*
G01X149663Y410083D02*
X151612Y412032D01*
Y412098D01*
X151579Y412131D01*
G01X157411Y398513D02*
X155604Y400320D01*
X155516D01*
G01X169113Y398299D02*
X167327Y400085D01*
Y400320D01*
G01X178031Y390023D02*
X176757D01*
X172011Y385277D01*
X168154D01*
X165090Y388341D01*
Y389214D01*
X163390Y390914D01*
Y392446D01*
G01X193016Y485443D02*
X199013D01*
X200788Y483668D01*
G01X151579Y431816D02*
X153549Y429846D01*
G01X165621Y418066D02*
X165546Y418141D01*
X165254D01*
X163390Y420005D01*
G01X151579Y427879D02*
X153549Y425909D01*
G01X161746Y421972D02*
X161609D01*
X159642Y420005D01*
X159453D01*
G01X177182Y467018D02*
X177017D01*
X176785Y467250D01*
X171264D01*
G01X175477Y472360D02*
X174304Y471187D01*
X171264D01*
G01X176815Y479061D02*
X171264D01*
G01X161473Y457213D02*
Y457392D01*
X163390Y459309D01*
Y459376D01*
G01Y475124D02*
X165360Y477094D01*
G01X216324Y473418D02*
X222982D01*
X224800Y471600D01*
G01X151579Y439690D02*
X153549Y437720D01*
G01X157560Y445484D02*
X155704Y443628D01*
X155516D01*
G01X186163Y438083D02*
X176809D01*
X171264Y443628D01*
G01X193915Y441633D02*
X193265Y440983D01*
X177846D01*
X171264Y447565D01*
G01X198615Y449033D02*
X198515Y449133D01*
X195400D01*
X189333Y455200D01*
X178973D01*
X173197Y460976D01*
X170601D01*
X169001Y459376D01*
X167327D01*
G01X151579Y447565D02*
X153549Y449535D01*
G01X174859Y469220D02*
X174602Y468963D01*
X170643D01*
X169363Y467683D01*
X168929Y467250D01*
X167327D01*
G01X174475Y488016D02*
Y487741D01*
X171969Y485235D01*
X169564D01*
X167327Y482998D01*
G01X157322Y453385D02*
X155569Y451632D01*
Y451555D01*
X155516Y451502D01*
G01X165317Y461561D02*
X165142D01*
X163390Y463313D01*
G01Y471187D02*
X165360Y473157D01*
G01X161455Y453385D02*
Y453437D01*
X159453Y455439D01*
G01X185266Y481893D02*
X182355D01*
X177955Y486293D01*
X177763D01*
G01X189516Y481243D02*
X188866Y481893D01*
X185266D01*
G01X149576Y465497D02*
Y465316D01*
X151579Y463313D01*
G01X153463Y453383D02*
X153460D01*
X151579Y451502D01*
G01X157411Y469344D02*
Y465208D01*
X155516Y463313D01*
G01X159453Y475124D02*
X161423Y477094D01*
G01X155516Y459376D02*
X157486Y461346D01*
G01X149563Y469220D02*
X151533Y467250D01*
X151579D01*
G01X153690Y469111D02*
Y469076D01*
X155516Y467250D01*
G01X165411Y429590D02*
Y429795D01*
X163390Y431816D01*
G01X175161Y434723D02*
X174053Y433615D01*
X169126D01*
X167327Y431816D01*
G01X202764Y444274D02*
X204700Y442338D01*
Y441000D01*
G01X190887Y424438D02*
X190188Y423739D01*
X184053D01*
X183409Y423095D01*
Y422985D01*
X180429Y420005D01*
X171264D01*
G01X185215Y418083D02*
X184932Y417800D01*
X181300D01*
G01X185359Y421839D02*
X185390Y421808D01*
Y418258D01*
X185215Y418083D01*
G01X188859Y421839D02*
X189415Y421283D01*
Y416983D01*
G01X174500Y424100D02*
X174342Y423942D01*
X171264D01*
G01X159453Y443628D02*
X161423Y445598D01*
G01X151579Y423942D02*
X153549Y421972D01*
G01X161423Y449430D02*
X161318D01*
X159453Y447565D01*
G01X176915Y446556D02*
X174536D01*
X171927Y449165D01*
X168927D01*
X167327Y447565D01*
G01X161670Y418161D02*
Y417788D01*
X163390Y416068D01*
G01X215006Y444201D02*
X215550Y444745D01*
Y449700D01*
G01D02*
Y453450D01*
X215100Y453900D01*
G01X212050Y449700D02*
X209800D01*
X207200Y447100D01*
G01X163390Y439690D02*
X164990Y441290D01*
X172470D01*
X176477Y437283D01*
X183710D01*
X185210Y435783D01*
X187116D01*
X188616Y437283D01*
X192818D01*
X202635Y447100D01*
X207200D01*
G01X192815Y433733D02*
X190534D01*
X186969Y430168D01*
X176049D01*
X174401Y431816D01*
X171264D01*
G01X153201Y418097D02*
Y418383D01*
X151579Y420005D01*
G01X186016Y432468D02*
X182001Y436483D01*
X174402D01*
X173939Y436020D01*
X171531D01*
X171264Y435753D01*
G01X186363Y444183D02*
Y444570D01*
X175494Y455439D01*
X171264D01*
G01X157401Y418143D02*
X157378D01*
X155516Y420005D01*
G01X186663Y450083D02*
X181982D01*
X175158Y456907D01*
Y457883D01*
X174163Y458878D01*
X171762D01*
X171264Y459376D01*
G01X157463Y421883D02*
Y421995D01*
X155516Y423942D01*
G01Y427879D02*
X157486Y425909D01*
G01X173458Y457178D02*
X169066D01*
X167327Y455439D01*
G01X178053Y474260D02*
X172663D01*
X171286Y472883D01*
X169163D01*
X167467Y471187D01*
X167327D01*
G01X174601Y481467D02*
X174174Y481040D01*
X169306D01*
X167327Y479061D01*
G01X165319Y453134D02*
X165022D01*
X163390Y451502D01*
G01X165353Y480812D02*
X163602Y479061D01*
X163390D01*
G01X155516Y435753D02*
X157486Y433783D01*
G01X163390Y423942D02*
X165360Y421972D01*
G01X153646Y457393D02*
Y457309D01*
X155516Y455439D01*
G01X161294Y461561D02*
X161205D01*
X159453Y463313D01*
G01X165363Y425783D02*
Y425906D01*
X163390Y427879D01*
G01X157393Y457572D02*
X159197Y459376D01*
X159453D01*
G01X165217Y457361D02*
Y457266D01*
X163390Y455439D01*
G01X181034Y427967D02*
Y426534D01*
X176713Y422213D01*
X168839D01*
X167327Y420701D01*
Y420005D01*
G01X177700Y427300D02*
X176478Y426078D01*
X169463D01*
X167327Y423942D01*
G01X189516Y485443D02*
X185316D01*
X185266Y485393D01*
G01D02*
X183949Y486710D01*
X180657D01*
X178417Y488949D01*
X177651Y489716D01*
X173770D01*
X171264Y487210D01*
Y486935D01*
G01X165355Y433382D02*
Y433788D01*
X163390Y435753D01*
G01X159453Y471187D02*
X161423Y473157D01*
G01X165355Y437582D02*
X165440Y437497D01*
X165583D01*
X167327Y435753D01*
G01X163390Y443628D02*
X165360Y445598D01*
G01X157411Y449556D02*
X159357Y451502D01*
X159453D01*
G01X169157Y445598D02*
Y445458D01*
X167327Y443628D01*
G01X157508Y480990D02*
X155579Y479061D01*
X155516D01*
G01X165288Y449306D02*
X165131D01*
X163390Y447565D01*
G01X157486Y484968D02*
X155516Y482998D01*
G01X153601Y480894D02*
X151768Y479061D01*
X151579D01*
G01X153586Y485118D02*
Y485005D01*
X151579Y482998D01*
G01X159453Y435753D02*
X161423Y433783D01*
G01X193016Y489543D02*
X195243D01*
X199618Y493918D01*
X200788D01*
G01X155181Y525492D02*
G03X156317Y528235I-2743J2743D01*
G01Y542055D01*
X155877Y542495D01*
Y543695D01*
X156317Y544135D01*
Y545335D01*
X155877Y545775D01*
Y546975D01*
X156317Y547415D01*
Y548615D01*
X155877Y549055D01*
Y550255D01*
X156317Y550695D01*
Y551750D01*
X155877Y552190D01*
Y553390D01*
X156317Y553830D01*
Y555030D01*
X155877Y555470D01*
Y556670D01*
X156317Y557110D01*
Y607255D01*
X155877Y607695D01*
Y608895D01*
X156317Y609335D01*
Y610535D01*
X155877Y610975D01*
Y612175D01*
X156317Y612615D01*
Y613815D01*
X155877Y614255D01*
Y615455D01*
X156317Y615895D01*
Y617200D01*
X155877Y617640D01*
Y618840D01*
X156317Y619280D01*
Y620480D01*
X155877Y620920D01*
Y622120D01*
X156317Y622560D01*
Y672955D01*
X155877Y673395D01*
Y674595D01*
X156317Y675035D01*
Y676283D01*
X155877Y676723D01*
Y677875D01*
X156317Y678315D01*
Y679500D01*
X155877Y679940D01*
Y681140D01*
X156317Y681580D01*
Y682780D01*
X155877Y683220D01*
Y684420D01*
X156317Y684860D01*
Y716728D01*
X156318D01*
G02X165054Y737822I29831J2D01*
G01X166666Y739434D01*
Y740056D01*
X167515Y740905D01*
X168137D01*
X168986Y741753D01*
Y742376D01*
X169834Y743224D01*
X170456D01*
X171262Y744030D01*
Y744652D01*
X172111Y745501D01*
X172733D01*
X206538Y779306D01*
G03X213470Y796041I-16735J16735D01*
G01Y831159D01*
G03X212006Y834694I-5000J0D01*
G01X206764Y839936D01*
G03X203229Y841400I-3535J-3536D01*
G01X180902D01*
G03X179875Y840974I1J-1453D01*
G01X179874Y840973D01*
G02X178848Y840549I-1026J1029D01*
G01X175118D01*
G01X163390Y490872D02*
X165360Y492842D01*
Y495247D01*
X166622Y496509D01*
X183991D01*
X186415Y498933D01*
X186515D01*
G01X210223Y501477D02*
X208264Y499518D01*
X193785D01*
X193770Y499533D01*
X187115D01*
X186515Y498933D01*
G01X163390Y494809D02*
X165912Y497331D01*
X178913D01*
X183200Y501618D01*
X202715D01*
G01X213500Y503600D02*
X209800D01*
X207818Y501618D01*
X202715D01*
G01X185266Y493093D02*
X178189D01*
X178084Y493198D01*
G01X189516Y493343D02*
X189266Y493093D01*
X185266D01*
G01X180845Y521961D02*
Y518057D01*
X181054Y517848D01*
G01X177324Y521977D02*
X178604Y520696D01*
G02X179115Y519464I-1232J-1233D01*
G01Y518762D01*
G02X178910Y518267I-700J0D01*
G01X178696Y518053D01*
G02X178201Y517848I-495J495D01*
G01X177099D01*
G01X177324Y525477D02*
G03X178368Y527997I-2520J2520D01*
G01Y530428D01*
G02X179580Y533357I4142J2D01*
G01X286999Y640776D01*
G02X287235Y641003I5980J-5980D01*
G02X293477Y643447I6240J-6744D01*
G01X294477D01*
X294877Y643847D01*
X295877D01*
X296277Y643447D01*
X297277D01*
X297677Y643847D01*
X298677D01*
X299077Y643447D01*
X769161D01*
G03X771868Y644568I0J3829D01*
G02X774577Y645690I2709J-2709D01*
G01X780514D01*
G01X180845Y525461D02*
X180748Y525557D01*
G02X179668Y528166I2609J2608D01*
G01Y530428D01*
G02X180500Y532437I2841J0D01*
G01X287900Y639837D01*
G02X293477Y642147I5577J-5577D01*
G01X771054D01*
G02X771609Y641917I0J-785D01*
G03X772000Y641755I391J391D01*
G01X780514D01*
G01X188363Y529753D02*
X188798Y530188D01*
G03X189300Y531400I-1212J1212D01*
G01Y534700D01*
G02X190349Y537234I3583J1D01*
G01X190658Y537542D01*
X280522Y627406D01*
G02X284723Y629145I4200J-4202D01*
G01X770728D01*
G03X771534Y629479I0J1140D01*
G02X772659Y629945I1125J-1125D01*
G01X780514D01*
G01X191863Y529753D02*
X190872Y530745D01*
G02X190600Y531400I655J656D01*
G01Y534700D01*
G02X191268Y536311I2279J-1D01*
G01X191428Y536472D01*
X281442Y626486D01*
G02X284723Y627845I3281J-3281D01*
G01X769754D01*
G02X771332Y627419I-1J-3141D01*
G02X771975Y626925I-1576J-2717D01*
G03X774196Y626005I2221J2221D01*
G01X780514D01*
G01X214163Y529553D02*
X213615Y530100D01*
G02X213054Y531456I1356J1355D01*
G01Y533733D01*
G02X214621Y537516I5350J0D01*
G01X274932Y597827D01*
G02X281359Y600489I6427J-6427D01*
G01X759050D01*
G02X764506Y598229I0J-7716D01*
G01X765402Y597333D01*
G03X769039Y595827I3637J3639D01*
G01X770242D01*
G02X771832Y595168I0J-2248D01*
G03X773421Y594510I1589J1590D01*
G01X780514D01*
G01X202963Y525453D02*
Y534496D01*
X202964Y534495D01*
G02X204659Y538838I6412J0D01*
G01X204839Y539032D01*
X271468Y605661D01*
X271839Y606033D01*
G02X284258Y611177I12419J-12419D01*
G01X770574D01*
G02X771682Y610718I0J-1567D01*
G03X772788Y610260I1106J1106D01*
G01X780514D01*
G01X210563Y529653D02*
X211321Y530412D01*
G03X211754Y531456I-1042J1044D01*
G01Y533733D01*
G02X213701Y538436I6650J1D01*
G01X274012Y598747D01*
G02X281359Y601789I7345J-7348D01*
G01X759051D01*
G02X765426Y599149I0J-9017D01*
G01X766322Y598253D01*
G03X769040Y597127I2718J2718D01*
G01X770195D01*
G03X771786Y597786I0J2250D01*
G02X773377Y598445I1591J-1591D01*
G01X780514D01*
G01X169812Y526197D02*
Y522245D01*
X170037Y522020D01*
G01X166180Y526196D02*
X167019Y525356D01*
G02X167817Y523431I-1925J-1926D01*
G01Y522720D01*
G02X167117Y522020I-700J0D01*
G01X165955D01*
G01X199363Y525453D02*
Y527117D01*
G02X200444Y528198I1081J0D01*
G03X201222Y528520I0J1101D01*
G01X201358Y528656D01*
X201663Y529392D01*
Y534495D01*
G02X203922Y539949I7713J0D01*
G01X203927Y539960D01*
X270112Y606144D01*
X270919Y606952D01*
G02X284253Y612477I13339J-13339D01*
G01X759100D01*
X759623Y613000D01*
X760600D01*
X761123Y612477D01*
X770236D01*
G03X771711Y613088I0J2086D01*
G01X772161Y613538D01*
G02X773747Y614195I1586J-1586D01*
G01X780514D01*
G01X158691Y521943D02*
G02X158917Y521397I-546J-546D01*
G01Y517830D01*
G01X214413Y521903D02*
X213739Y521230D01*
G03X213192Y519908I1322J-1321D01*
G01Y514986D01*
G02X211554Y511029I-5595J-1D01*
G01X206702Y506177D01*
G02X206701Y506176I-4716J4715D01*
G02X201893Y504185I-4808J4810D01*
G01X184076D01*
G03X180706Y502789I0J-4766D01*
G01X178728Y500811D01*
G02X172550Y498253I-6177J6178D01*
G01X160852D01*
G03X160178Y497973I1J-952D01*
G01X159069Y496864D01*
X158475Y496271D01*
X158082Y495878D01*
G03X157778Y495144I734J-734D01*
G01Y494583D01*
G02X156753Y492110I-3498J1D01*
G01X155516Y490872D01*
G01X214163Y526053D02*
Y522153D01*
X214413Y521903D01*
G01X210313Y522003D02*
X211527Y520789D01*
G02X211892Y519908I-881J-881D01*
G01Y514986D01*
G02X210634Y511949I-4295J0D01*
G01X205781Y507096D01*
G02X201892Y505485I-3889J3889D01*
G01X184075D01*
G03X179786Y503709I0J-6067D01*
G01X177808Y501731D01*
G02X172550Y499553I-5258J5258D01*
G01X160851D01*
G03X159258Y498893I0J-2253D01*
G01X155758Y495393D01*
G03X155516Y494809I584J-584D01*
G01X210563Y526153D02*
X211582Y525134D01*
G02X212362Y523251I-1883J-1883D01*
G01Y523018D01*
G02X212197Y522620I-563J0D01*
G01X211785Y522208D01*
G02X211290Y522003I-495J495D01*
G01X210313D01*
G01X203213Y517803D02*
X202932Y517523D01*
G03X202052Y515397I2126J-2125D01*
G01Y513826D01*
G02X201087Y511494I-3297J-1D01*
G01X199680Y510087D01*
G02X196772Y508884I-2906J2908D01*
G01X189566D01*
G03X189052Y508671I0J-727D01*
G01X189050Y508669D01*
G02X186632Y507669I-2416J2418D01*
G01X183543D01*
G03X179125Y505839I0J-6248D01*
G01X177009Y503723D01*
G02X172732Y501953I-4275J4277D01*
G01X161688D01*
G03X158863Y500783I0J-3995D01*
G01X153678Y495598D01*
G03X153254Y494574I1024J-1024D01*
G01Y494383D01*
G02X151956Y491249I-4432J0D01*
G01X151579Y490872D01*
G01X202963Y521953D02*
Y518407D01*
G03X203213Y517803I854J0D01*
G01X199113D02*
X200210Y516707D01*
G02X200752Y515397I-1310J-1309D01*
G01Y513826D01*
G02X200167Y512414I-1997J0D01*
G01X198760Y511007D01*
G02X196773Y510184I-1987J1987D01*
G01X189565D01*
G03X188132Y509591I0J-2028D01*
G01X188130Y509589D01*
G02X187805Y509323I-1497J1497D01*
G02X186633Y508969I-1172J1763D01*
G01X183542D01*
G03X178205Y506759I0J-7549D01*
G01X176089Y504643D01*
G02X172733Y503253I-3356J3356D01*
G01X161829D01*
G03X157843Y501602I0J-5637D01*
G01X151953Y495712D01*
G03X151579Y494809I903J-903D01*
G01X199363Y521953D02*
Y518407D01*
G02X199113Y517803I-854J0D01*
G01X191863Y526253D02*
Y522607D01*
G03X192113Y522003I854J0D01*
G01X188363Y526253D02*
X189622Y524994D01*
G02X190254Y523468I-1526J-1526D01*
G01Y522701D01*
G02X190050Y522207I-698J-1D01*
G01X190049Y522206D01*
G02X189557Y522003I-492J495D01*
G01X188113D01*
G01X155181Y521992D02*
X156422Y520751D01*
G02X156727Y520015I-736J-736D01*
G01Y518631D01*
G02X155975Y517879I-752J0D01*
G01X154924D01*
G01X189516Y489543D02*
X189466Y489593D01*
X185266D01*
G01D02*
X183683Y488010D01*
X181196D01*
X178190Y491016D01*
X171408D01*
X171264Y490872D01*
G01X169812Y529697D02*
G02X168616Y532584I2887J2887D01*
G01Y721896D01*
G02X174971Y737238I21697J0D01*
G01X212172Y774439D01*
G03X219414Y791923I-17483J17483D01*
G01Y837430D01*
G03X216161Y845284I-11106J1D01*
G01X213778Y847667D01*
G03X202199Y852463I-11578J-11578D01*
G01X180771D01*
G02X179943Y852806I0J1171D01*
G03X179115Y853149I-828J-828D01*
G01X175118D01*
G01X166180Y529696D02*
G03X167316Y532439I-2743J2743D01*
G01Y539821D01*
X166899Y540238D01*
Y541221D01*
X167316Y541638D01*
Y542621D01*
X166899Y543038D01*
Y544021D01*
X167316Y544438D01*
Y545421D01*
X166899Y545838D01*
Y546821D01*
X167316Y547238D01*
Y548221D01*
X166899Y548638D01*
Y549621D01*
X167316Y550038D01*
Y551021D01*
X166899Y551438D01*
Y552421D01*
X167316Y552838D01*
Y553821D01*
X166899Y554238D01*
Y555221D01*
X167316Y555638D01*
Y721897D01*
G02X174051Y738157I22997J-1D01*
G01X211253Y775359D01*
G03X218114Y791923I-16564J16564D01*
G01Y837430D01*
G03X215242Y844364I-9806J0D01*
G01X212858Y846748D01*
G03X202199Y851163I-10659J-10659D01*
G01X181125D01*
G03X179507Y850493I0J-2288D01*
G02X178314Y849999I-1193J1193D01*
G01X175118D01*
G01X158691Y525443D02*
G02X157617Y528036I2593J2593D01*
G01Y716728D01*
G02X165974Y736902I28531J-1D01*
G01X166919Y737848D01*
X207458Y778386D01*
G03X214770Y796040I-17656J17654D01*
G01Y831159D01*
G03X212926Y835614I-6300J1D01*
G01X207684Y840856D01*
G03X203229Y842700I-4454J-4456D01*
G01X180806D01*
G02X179601Y843200I1J1705D01*
G01X179600Y843201D01*
G03X178396Y843699I-1204J-1206D01*
G01X175118D01*
G01X219590Y740816D02*
Y740508D01*
X217015Y737933D01*
G01X219303Y748164D02*
X213484D01*
X213415Y748233D01*
G01X159589Y817543D02*
Y817593D01*
G02X159940Y818440I1198J0D01*
G01X161286Y819786D01*
G02X161993Y820079I707J-706D01*
G01X165238D01*
G01X159688Y832484D02*
G02X160159Y832679I471J-471D01*
G01X165238D01*
G01X159688Y829234D02*
G02X160400Y829529I712J-712D01*
G01X165238D01*
G01X159137Y820712D02*
G02X165214Y823229I6077J-6077D01*
G01X165238D01*
G01X159688Y851564D02*
X159698Y851574D01*
X165238D01*
G01X159560Y842172D02*
X159562D01*
X159610Y842124D01*
X165238D01*
G01X159426Y848357D02*
X159493Y848424D01*
X165238D01*
G01Y838974D02*
X159431D01*
G01X250140Y89833D02*
X250540Y89433D01*
X253552D01*
X254498Y88487D01*
G01X223129Y188760D02*
Y182346D01*
X223817Y181658D01*
G01D02*
X226742D01*
X227900Y180500D01*
G01X220569Y188760D02*
Y182685D01*
X219504Y181620D01*
G01X223817Y178158D02*
Y174423D01*
X223948Y174292D01*
G01X219504Y178120D02*
Y174695D01*
X219548Y174651D01*
G01X235215Y182933D02*
X227927D01*
X225689Y185171D01*
Y188760D01*
G01X227152Y214585D02*
X225689Y213122D01*
Y204940D01*
G01X227116Y218917D02*
Y214621D01*
X227152Y214585D01*
G01X227116Y223400D02*
Y218917D01*
G01X235700Y204940D02*
X228249D01*
G01X231350Y214158D02*
X228249Y211057D01*
Y204940D01*
G01X235414Y214263D02*
X235309Y214158D01*
X231350D01*
G01X223129Y210901D02*
Y204940D01*
G01X224664Y293860D02*
X657689D01*
X695032Y331203D01*
X746715D01*
G01X232100Y414550D02*
Y413892D01*
X228949Y410741D01*
G01X227900Y414550D02*
Y413387D01*
X225421Y410908D01*
G01X234222Y392396D02*
X234779D01*
X240041Y387134D01*
X240662D01*
G01D02*
X241496Y386300D01*
X245100D01*
G01X249103Y387029D02*
X245829D01*
X245100Y386300D01*
G01X249091Y383206D02*
X249103Y383218D01*
Y387029D01*
G01X232708Y405205D02*
X232611Y405302D01*
X224403D01*
G01X232708Y405205D02*
X234222Y403691D01*
Y399876D01*
G01X224885Y356264D02*
G03X223805Y353657I2607J-2607D01*
G01Y353400D01*
G03X224832Y350922I3503J0D01*
G01X224936Y350817D01*
G03X228554Y349575I3618J4648D01*
G01X295080D01*
X295520Y350015D01*
X296720D01*
X297160Y349575D01*
X298360D01*
X298800Y350015D01*
X300000D01*
X300440Y349575D01*
X301640D01*
X302080Y350015D01*
X303280D01*
X303720Y349575D01*
X304920D01*
X305360Y350015D01*
X306560D01*
X307000Y349575D01*
X308200D01*
X308640Y350015D01*
X309840D01*
X310280Y349575D01*
X360280D01*
X360720Y350015D01*
X361920D01*
X362360Y349575D01*
X363560D01*
X364000Y350015D01*
X365200D01*
X365640Y349575D01*
X366840D01*
X367280Y350015D01*
X368480D01*
X368920Y349575D01*
X370120D01*
X370560Y350015D01*
X371760D01*
X372200Y349575D01*
X373400D01*
X373840Y350015D01*
X375040D01*
X375480Y349575D01*
X425480D01*
X425920Y350015D01*
X427120D01*
X427560Y349575D01*
X428760D01*
X429200Y350015D01*
X430400D01*
X430840Y349575D01*
X432040D01*
X432480Y350015D01*
X433680D01*
X434120Y349575D01*
X435320D01*
X435760Y350015D01*
X436960D01*
X437400Y349575D01*
X438600D01*
X439040Y350015D01*
X440240D01*
X440680Y349575D01*
X490680D01*
X491120Y350015D01*
X492320D01*
X492760Y349575D01*
X493960D01*
X494400Y350015D01*
X495600D01*
X496040Y349575D01*
X497240D01*
X497680Y350015D01*
X498880D01*
X499320Y349575D01*
X500520D01*
X500960Y350015D01*
X502160D01*
X502600Y349575D01*
X506120D01*
G03X509302Y350893I0J4500D01*
G01X648521Y490112D01*
G02X651703Y491430I3182J-3182D01*
G01X725611D01*
G03X726948Y491984I0J1890D01*
G01X727502Y492538D01*
G02X733591Y495060I6090J-6091D01*
G01X769938D01*
G03X769970I16J1502D01*
G03X770977Y495477I0J1424D01*
G01X771000Y495500D01*
G02X772412Y496085I1412J-1412D01*
G01X780514D01*
G01X221424Y356317D02*
G02X222505Y353707I-2610J-2610D01*
G01Y353400D01*
G03X223910Y350004I4804J-1D01*
G01X224068Y349845D01*
G03X224529Y349506I4487J5619D01*
G03X228555Y348275I4023J5959D01*
G01X506120D01*
G03X510222Y349973I1J5801D01*
G01X649441Y489192D01*
G02X651703Y490130I2263J-2262D01*
G01X725611D01*
G03X727868Y491064I1J3191D01*
G01X728422Y491618D01*
G02X733592Y493760I5171J-5171D01*
G01X770498D01*
G02X771338Y493412I0J-1188D01*
G02X771948Y492952I-1339J-2410D01*
G03X773896Y492145I1948J1948D01*
G01X780514D01*
G01X245105Y375055D02*
G03X247794Y373941I2689J2689D01*
G01X432771D01*
G03X435033Y374879I-1J3200D01*
G01X571114Y510960D01*
Y511582D01*
X571963Y512431D01*
X572585D01*
X573434Y513280D01*
Y513902D01*
X574282Y514750D01*
X574904D01*
X575753Y515599D01*
Y516221D01*
X576601Y517070D01*
X577224D01*
X612579Y552425D01*
Y553047D01*
X613428Y553896D01*
X614050D01*
X614898Y554744D01*
Y555367D01*
X615747Y556215D01*
X616369D01*
X617218Y557064D01*
Y557686D01*
X618066Y558534D01*
X618688D01*
X619537Y559383D01*
Y560005D01*
X620385Y560854D01*
X621008D01*
X621856Y561702D01*
Y562324D01*
X622705Y563173D01*
X623327D01*
X639803Y579649D01*
G02X643905Y581347I4101J-4103D01*
G01X685200D01*
X685640Y581787D01*
X686840D01*
X687280Y581347D01*
X688480D01*
X688920Y581787D01*
X690120D01*
X690560Y581347D01*
X691760D01*
X692200Y581787D01*
X693400D01*
X693840Y581347D01*
X695040D01*
X695480Y581787D01*
X696680D01*
X697120Y581347D01*
X698320D01*
X698760Y581787D01*
X699960D01*
X700400Y581347D01*
X750400D01*
X750840Y581787D01*
X752040D01*
X752480Y581347D01*
X753680D01*
X754120Y581787D01*
X755320D01*
X755760Y581347D01*
X756960D01*
X757400Y581787D01*
X758600D01*
X759040Y581347D01*
X760240D01*
X760680Y581787D01*
X761880D01*
X762320Y581347D01*
X763520D01*
X763960Y581787D01*
X765160D01*
X765600Y581347D01*
X770639D01*
G03X771426Y581673I0J1113D01*
G01X771726Y581973D01*
G02X773481Y582700I1755J-1755D01*
G01X780514D01*
G01X249415Y363969D02*
G03X252174Y362826I2759J2759D01*
G01X298960D01*
X299400Y363266D01*
X300600D01*
X301040Y362826D01*
X302240D01*
X302680Y363266D01*
X303880D01*
X304320Y362826D01*
X305520D01*
X305960Y363266D01*
X307160D01*
X307600Y362826D01*
X357600D01*
X358040Y363266D01*
X359240D01*
X359680Y362826D01*
X360880D01*
X361320Y363266D01*
X362520D01*
X362960Y362826D01*
X364160D01*
X364600Y363266D01*
X365800D01*
X366240Y362826D01*
X367440D01*
X367880Y363266D01*
X369080D01*
X369520Y362826D01*
X370720D01*
X371160Y363266D01*
X372360D01*
X372800Y362826D01*
X422800D01*
X423240Y363266D01*
X424440D01*
X424880Y362826D01*
X426080D01*
X426520Y363266D01*
X427720D01*
X428160Y362826D01*
X429360D01*
X429800Y363266D01*
X431000D01*
X431440Y362826D01*
X432640D01*
X433080Y363266D01*
X434280D01*
X434720Y362826D01*
X435920D01*
X436360Y363266D01*
X437560D01*
X438000Y362826D01*
X488000D01*
X488440Y363266D01*
X489640D01*
X490080Y362826D01*
X491280D01*
X491720Y363266D01*
X492920D01*
X493360Y362826D01*
X494560D01*
X495000Y363266D01*
X496200D01*
X496640Y362826D01*
X497840D01*
X498280Y363266D01*
X499480D01*
X499920Y362826D01*
X501120D01*
X501560Y363266D01*
X502760D01*
X503200Y362826D01*
X513022D01*
G03X515284Y363764I-1J3200D01*
G01X649934Y498414D01*
G02X654036Y500112I4101J-4103D01*
G01X711321D01*
G03X714502Y501430I-1J4500D01*
G01X741322Y528251D01*
G02X746023Y530197I4700J-4702D01*
G01X770565D01*
G03X772156Y530856I0J2250D01*
G02X773747Y531515I1591J-1591D01*
G01X780514D01*
G01X245080Y371576D02*
X245614Y372110D01*
G02X246896Y372641I1282J-1282D01*
G01X248413D01*
G03X248417I2J814D01*
G01X432771D01*
G03X435953Y373959I0J4500D01*
G01X640723Y578729D01*
G02X643905Y580047I3182J-3182D01*
G01X770343D01*
G02X771393Y579778I-3J-2196D01*
G02X771458Y579742I-1031J-1939D01*
G02X771896Y579404I-1112J-1894D01*
G03X773451Y578760I1555J1555D01*
G01X780514D01*
G01X249378Y360456D02*
X250200Y361279D01*
G02X250798Y361526I597J-598D01*
G01X513022D01*
G03X516204Y362844I0J4500D01*
G01X650854Y497494D01*
G02X654036Y498812I3182J-3182D01*
G01X711320D01*
G03X715422Y500510I1J5801D01*
G01X742242Y527331D01*
G02X746023Y528897I3781J-3781D01*
G01X770537D01*
G02X771845Y528355I0J-1849D01*
G01X771961Y528238D01*
G03X773551Y527580I1589J1590D01*
G01X780514D01*
G01X221424Y359817D02*
Y363625D01*
X221135Y363914D01*
G01X224885Y359764D02*
Y363703D01*
X225089Y363907D01*
G01X245878Y360456D02*
X241978D01*
X241728Y360206D01*
G01X245915Y363969D02*
X241965D01*
X241728Y364206D01*
G01X241580Y371576D02*
X237726D01*
X237455Y371305D01*
G01X241605Y375055D02*
X237705D01*
X237455Y375305D01*
G01X231108Y467587D02*
X227046D01*
X226992Y467533D01*
G01D02*
Y469408D01*
X224800Y471600D01*
G01X244500Y461100D02*
Y463800D01*
X246792Y466092D01*
X248410D01*
G01X238649Y461252D02*
X238786Y461115D01*
X244500Y461100D01*
G01X235149Y461252D02*
Y464860D01*
X235069Y464940D01*
G01X235250Y482954D02*
Y485550D01*
X233700Y487100D01*
G01X242900Y483600D02*
X239396D01*
X238750Y482954D01*
G01D02*
Y481411D01*
X235556Y478217D01*
G01X228001Y474064D02*
X228000D01*
Y478400D01*
G01X235266Y473688D02*
X228377D01*
X228001Y474064D01*
G01X238766Y473688D02*
Y471216D01*
X236473Y468923D01*
G01X238766Y473688D02*
X242812D01*
X242900Y473600D01*
G01X235250Y428000D02*
Y424850D01*
X238000Y422100D01*
G01Y418150D02*
Y422100D01*
G01X227750Y428000D02*
Y422450D01*
X227400Y422100D01*
G01X227900Y418050D02*
X227400Y418550D01*
Y422100D01*
G01X232750Y428000D02*
Y422200D01*
G01X232100Y418050D02*
Y421550D01*
X232750Y422200D01*
G01X243900Y424500D02*
Y424700D01*
X242653Y425947D01*
Y428291D01*
G01X242647Y432409D02*
X240728D01*
X238037Y435100D01*
X227850D01*
X225250Y432500D01*
Y428000D01*
G01X242653Y428291D02*
X242647Y428297D01*
Y432409D01*
G01X229300Y442500D02*
X226200D01*
X225250Y443450D01*
Y448600D01*
G01X222750Y428000D02*
Y432263D01*
X227187Y436700D01*
X242550D01*
X242700Y436550D01*
G01X246800D02*
X250550D01*
X250800Y436300D01*
G01X242700Y436550D02*
X246800D01*
G01X228400Y486400D02*
X229100Y487100D01*
X233700D01*
G01X223129Y755690D02*
Y748693D01*
X223658Y748164D01*
G01X229715Y747933D02*
X229484Y748164D01*
X223658D01*
G01X225689Y755690D02*
Y752159D01*
X227315Y750533D01*
X231015D01*
X235715Y755233D01*
G01X223671Y740896D02*
X226015Y738552D01*
Y737933D01*
G01X223658Y744664D02*
Y740909D01*
X223671Y740896D01*
G01X219303Y744664D02*
Y741103D01*
X219590Y740816D01*
G01X220569Y755690D02*
Y749430D01*
X219303Y748164D01*
G01X223129Y771870D02*
Y764830D01*
G01X225689Y771870D02*
Y775077D01*
X226879Y776267D01*
X228369D01*
X231112Y779010D01*
G01X234716Y783159D02*
X240189D01*
X240615Y782733D01*
G01X231112Y779010D02*
Y779555D01*
X234716Y783159D01*
G01X228249Y771870D02*
X233987D01*
X234524Y771333D01*
G01D02*
X240715D01*
G01D02*
X243064Y773682D01*
Y783584D01*
X239313Y787335D01*
X234671D01*
G01X334696Y793055D02*
X333642Y792001D01*
X324060D01*
X320192Y788133D01*
X251138D01*
X243853Y795418D01*
X236973D01*
G01X285792Y794780D02*
X285735Y794837D01*
Y817088D01*
X286982Y818335D01*
G01X235169Y791455D02*
X235248Y791376D01*
X241374D01*
X246217Y786533D01*
X321845D01*
X325013Y789701D01*
G01X240130Y789012D02*
X240198D01*
X244277Y784933D01*
X327515D01*
X328674Y786092D01*
X333871D01*
G01X319165Y795010D02*
Y799303D01*
X316490Y801978D01*
Y817843D01*
X316982Y818335D01*
G01X297626Y794808D02*
Y799646D01*
X295658Y801614D01*
Y817011D01*
X296982Y818335D01*
G01X308949Y794862D02*
Y800836D01*
X306927Y802858D01*
Y818280D01*
X306982Y818335D01*
G01X342784Y792836D02*
Y814137D01*
X346982Y818335D01*
G01X338196Y793055D02*
X338415Y792836D01*
X342784D01*
G01X353977Y792923D02*
X350755Y789701D01*
X325013D01*
G01X357950Y792962D02*
X351080Y786092D01*
X333871D01*
G01X742300Y569500D02*
X735000D01*
X732212Y572288D01*
X638680D01*
X471548Y405156D01*
Y387965D01*
X473838Y385675D01*
G01X474106Y382285D02*
X477013Y385192D01*
Y400253D01*
X581860Y505100D01*
X707700D01*
X719467Y516867D01*
Y520167D01*
X719800Y520500D01*
Y520512D01*
X720700Y521412D01*
Y521424D01*
X723276Y524000D01*
X723288D01*
X723488Y524200D01*
X726500D01*
X741600Y539300D01*
Y541600D01*
G01X644415Y560714D02*
X632614D01*
X475413Y403513D01*
Y390876D01*
X473605Y389068D01*
G01X490949Y508498D02*
X494999D01*
X498148Y505349D01*
Y489168D01*
X498994Y488322D01*
G01D02*
X499376Y487940D01*
X502755D01*
X535957Y521142D01*
Y527708D01*
X533583Y530083D01*
X533582D01*
X532021Y531644D01*
X528860D01*
G01X490952Y512828D02*
X493472D01*
X500048Y506252D01*
Y491994D01*
X501802Y490240D01*
G01X451015Y514433D02*
X450868Y514286D01*
Y508324D01*
G01D02*
X452294Y506898D01*
X455098D01*
X455894Y506102D01*
X460020D01*
G01X487452Y512828D02*
X483200D01*
G01X476320Y508067D02*
X479967D01*
X481600Y509700D01*
Y511228D01*
X483200Y512828D01*
G01X476320Y506102D02*
X481704D01*
X483402Y507800D01*
G01X487449Y508498D02*
X484100D01*
X483402Y507800D01*
G01X460020Y508067D02*
Y510020D01*
X462213Y512213D01*
Y514834D01*
G01X466345D02*
Y516955D01*
X464300Y519000D01*
G01X462213Y514834D02*
X466345D01*
G01X497166Y537679D02*
X493679D01*
X492700Y536700D01*
Y534775D01*
X490880Y532955D01*
G01D02*
Y528635D01*
X490887Y528628D01*
G01D02*
Y524713D01*
X490900Y524700D01*
G01X503300Y539700D02*
X502761Y540239D01*
X497166D01*
G01X490888Y541335D02*
X492365D01*
X493461Y540239D01*
X497166D01*
G01X490933Y537159D02*
X490888Y537204D01*
Y541335D01*
G01X491300Y553900D02*
X490573Y553173D01*
Y549911D01*
G01D02*
Y545735D01*
X490663Y545645D01*
G01D02*
X493509Y542799D01*
X497166D01*
G01X537842Y407738D02*
X537155Y408425D01*
X530634D01*
G01D02*
X526766D01*
X516766Y418425D01*
X510634D01*
G01X537500Y401600D02*
X537200Y401300D01*
Y397850D01*
G01X532700Y397400D02*
X536750D01*
X537200Y397850D01*
G01X510634Y408425D02*
X516573D01*
X521573Y403425D01*
X530634D01*
G01X532700Y397400D02*
Y401359D01*
X530634Y403425D01*
G01X532750Y393000D02*
Y397350D01*
X532700Y397400D01*
G01X529250Y393000D02*
Y388950D01*
X529200Y388900D01*
G01X520900Y393600D02*
X528650D01*
X529250Y393000D01*
G01X508150Y389700D02*
Y393250D01*
X508500Y393600D01*
G01X513500Y391040D02*
X511040D01*
X509750Y389750D01*
X508200D01*
X508150Y389700D01*
G01X508500Y393600D02*
X513500D01*
G01X508306Y428179D02*
Y428524D01*
X511015Y431233D01*
G01X508284Y424179D02*
Y428157D01*
X508306Y428179D01*
G01X511784Y424179D02*
X510634Y423029D01*
Y418425D01*
G01X515966Y424009D02*
X511954D01*
X511784Y424179D01*
G01X501802Y490240D02*
X502367D01*
X534057Y521930D01*
Y526200D01*
X532787Y527470D01*
X528838D01*
G01X519366Y537679D02*
X513140D01*
X511055Y535594D01*
Y530821D01*
X513387Y528489D01*
X524319D01*
X525338Y527470D01*
G01D02*
Y523500D01*
G01X519366Y540239D02*
X523219D01*
X525463Y542483D01*
G01D02*
X529517D01*
X529800Y542200D01*
G01X525800Y535900D02*
X525360Y535460D01*
Y531644D01*
G01D02*
X524105Y530389D01*
X514175D01*
X512955Y531609D01*
Y534339D01*
X513735Y535119D01*
X519366D01*
G01X637200Y393900D02*
X637900Y394600D01*
X641400D01*
G01X645650D02*
X641400D01*
G01X653500D02*
X662100D01*
G01X649150D02*
X653500D01*
G01X711459Y453923D02*
G03X711650Y453462I652J0D01*
G01X713778Y451334D01*
X716331Y448757D01*
X716343Y448745D01*
G03X719316Y447514I2973J2974D01*
G01X750577D01*
G03X757388Y450335I1J9631D01*
G01X766314Y459261D01*
X766520Y459468D01*
G02X768761Y461078I6040J-6043D01*
G02X769766Y461499I3797J-7654D01*
G01X770495D01*
G02X771700Y461000I0J-1704D01*
G03X772545Y460650I845J845D01*
G01X780514D01*
G01X669959Y462023D02*
Y461885D01*
X667245Y459171D01*
G02X664942Y458217I-2303J2303D01*
G01X664303D01*
G03X662880Y457627I1J-2013D01*
G01X662166Y456914D01*
G01X665909Y466173D02*
X667362Y464720D01*
G02X667903Y463414I-1306J-1306D01*
G01Y462258D01*
G02X667486Y461251I-1424J0D01*
G01X666211Y459976D01*
G02X665103Y459517I-1108J1108D01*
G01X663141D01*
G02X661760Y460089I0J1953D01*
G01X649359Y482723D02*
X650852Y481229D01*
G02X651304Y480138I-1091J-1091D01*
G01Y478614D01*
G02X650833Y477477I-1608J0D01*
G01X649294Y475938D01*
G02X647536Y475210I-1758J1758D01*
G01X647396D01*
G02X646456Y475751I534J2014D01*
G01X646246Y475961D01*
G01X653459Y478423D02*
Y478263D01*
X651564Y476368D01*
X651563D01*
X650623Y475428D01*
Y475427D01*
X650214Y475018D01*
G02X648545Y474046I-2677J2678D01*
G03X647733Y473573I490J-1775D01*
G01X646794Y472634D01*
G01X673459Y462023D02*
X672824Y462659D01*
G02X672311Y463896I1237J1238D01*
G02X672643Y464397I1401J-568D01*
G02X673171Y464502I527J-1268D01*
G01X716477D01*
G02X717411Y464115I0J-1321D01*
G02X717203Y462967I-931J-424D01*
G01X716259Y462023D01*
G01X720359Y466123D02*
G02X719584Y465802I-775J775D01*
G01X670134D01*
G02X669359Y466123I0J1096D01*
G01X732759Y478623D02*
X733803Y479667D01*
G03Y481014I-674J673D01*
G03X732574Y481523I-1229J-1229D01*
G01X657232D01*
G03X656003Y481014I0J-1738D01*
G03Y479379I818J-818D01*
G01X656959Y478423D01*
G01X652859Y482723D02*
X652959Y482823D01*
X736859D01*
G01X707959Y453923D02*
X708883Y454848D01*
G03X709203Y455619I-771J772D01*
G03X708853Y456464I-1195J0D01*
G03X708228Y456723I-625J-625D01*
G01X681603D01*
G03X680993Y456471I-1J-862D01*
G01X680805Y456282D01*
G03X680617Y455828I454J-454D01*
G01Y455391D01*
G03X680848Y454835I787J1D01*
G01X681959Y453723D01*
G01X712059Y458023D02*
X677659D01*
X677559Y457923D01*
G01X724459Y470223D02*
X725403Y471167D01*
G03Y472714I-774J774D01*
G03X724657Y473023I-746J-746D01*
G01X664990D01*
G03X664003Y472614I0J-1396D01*
G03Y471379I618J-617D01*
G01X665159Y470223D01*
G01X661059Y474323D02*
X728459D01*
X728659Y474523D01*
G01X674109Y454473D02*
X671270D01*
X671145Y454348D01*
G01X661709Y466773D02*
G03X659856Y466006I0J-2622D01*
G03X659855Y466005I1853J-1854D01*
G01X658195Y464344D01*
Y464248D01*
G01X653351Y470098D02*
X653578Y470326D01*
G02X654900Y470873I1321J-1322D01*
G01X657609D01*
G01X670009Y458573D02*
G02X669853Y458198I-531J1D01*
G01X667745Y456089D01*
G01X665909Y462673D02*
X664079D01*
G02X662604Y463284I0J2086D01*
G01X650837Y472421D02*
G02X651164Y473212I1118J1D01*
G01X651501Y473548D01*
X652601Y474648D01*
G02X653386Y474973I785J-785D01*
G01X653509D01*
G01X646251Y479161D02*
X649297D01*
X649409Y479273D01*
G01X678509Y450273D02*
X677829D01*
X675745Y448189D01*
G01X711409Y450473D02*
G02X712806Y449895I1J-1975D01*
G01X713075Y449625D01*
X713400Y449300D01*
G02X713845Y448226I-1074J-1074D01*
G01Y447289D01*
G01X692450Y537000D02*
Y535050D01*
X689500Y532100D01*
G01D02*
Y531633D01*
X684195Y526328D01*
X682000D01*
G01X697600Y560000D02*
X699400Y558200D01*
X705612D01*
X708012Y555800D01*
X733700D01*
X736600Y552900D01*
X748350D01*
X749450Y551800D01*
G01X688250Y544300D02*
X688050Y544500D01*
X683600D01*
X680100Y541000D01*
G01D02*
Y539000D01*
X677375Y536275D01*
Y533512D01*
G01X701400Y560200D02*
X701500Y560100D01*
X706400D01*
X708600Y557900D01*
X734288D01*
X737388Y554800D01*
X748350D01*
X749450Y555900D01*
G01X749487Y560714D02*
X737186D01*
X730500Y567400D01*
X670986D01*
X664300Y560714D01*
X644415D01*
G01X667982Y739870D02*
X668330D01*
X683866Y755406D01*
Y757955D01*
X683999Y758088D01*
Y772687D01*
X685328Y774016D01*
X696098D01*
G01X681402Y757754D02*
X682399Y758751D01*
Y772958D01*
X682410Y772969D01*
Y773527D01*
X685399Y776516D01*
X696098D01*
G01X663575Y742289D02*
Y759784D01*
X685388Y781597D01*
X696017D01*
X696098Y781516D01*
G01X689190Y768056D02*
Y765808D01*
X687315Y763933D01*
Y762233D01*
G01X696098Y779016D02*
X685778D01*
X685707Y778945D01*
G01X680480Y773302D02*
X680810Y773632D01*
Y774190D01*
X685565Y778945D01*
X685707D01*
G01X678755Y784815D02*
X678880D01*
X679679Y784016D01*
X696098D01*
G01X676727Y790555D02*
X680766Y786516D01*
X696098D01*
G01X679630Y795856D02*
X686594Y788892D01*
X695974D01*
X696098Y789016D01*
G01X680239Y802378D02*
Y799903D01*
X688626Y791516D01*
X696098D01*
G01X682693Y806283D02*
Y800507D01*
X689184Y794016D01*
X696098D01*
G01X684732Y810518D02*
Y801568D01*
X689784Y796516D01*
X696098D01*
G01X669886Y786112D02*
X668316Y787682D01*
Y817962D01*
X682273Y831919D01*
X695412D01*
G01X686308Y834802D02*
X686691Y834419D01*
X695412D01*
G01X666516Y784722D02*
Y824702D01*
X676485Y834671D01*
X686177D01*
X686308Y834802D01*
G01X646342Y826469D02*
X658707Y838834D01*
X684767D01*
X686682Y836919D01*
X695412D01*
G01X689190Y771556D02*
X686461D01*
X685799Y770894D01*
G01X685215Y823933D02*
X688683Y827401D01*
X690211D01*
G01D02*
X692229Y829419D01*
X695412D01*
G01X696098Y771516D02*
X692650D01*
X689190Y768056D01*
G01X683715Y852233D02*
Y854268D01*
X685108Y855661D01*
G01D02*
X687639D01*
X689486Y853814D01*
Y848487D01*
X691054Y846919D01*
X695412D01*
G01X679332Y841866D02*
X683998D01*
X686445Y839419D01*
X695412D01*
G01X681156Y844982D02*
X687409D01*
X690472Y841919D01*
X695412D01*
G01X681542Y848361D02*
X686293D01*
X690235Y844419D01*
X695412D01*
G01X780514Y330730D02*
X774100D01*
X773330Y331500D01*
X747012D01*
X746715Y331203D01*
G01X758200Y338900D02*
X760300Y336800D01*
X767500D01*
X769635Y334665D01*
X780514D01*
G01X756700Y370600D02*
X758400Y368900D01*
X771200D01*
X772400Y370100D01*
X780514D01*
G01X715509Y457973D02*
G03X715115Y457810I0J-558D01*
G01X714599Y457294D01*
G03X713562Y454790I2505J-2504D01*
G01Y453964D01*
G03X713968Y452984I1386J0D01*
G01X714697Y452255D01*
X717263Y449665D01*
G03X719316Y448814I2054J2054D01*
G01X728523D01*
X729009Y449300D01*
X730209D01*
X730695Y448814D01*
X731895D01*
X732381Y449300D01*
X733581D01*
X734067Y448814D01*
X735267D01*
X735753Y449300D01*
X736953D01*
X737439Y448814D01*
X738639D01*
X739125Y449300D01*
X740325D01*
X740811Y448814D01*
X750577D01*
G03X756468Y451254I0J8331D01*
G01X765393Y460179D01*
X765599Y460387D01*
G02X768182Y462243I6961J-6962D01*
G02X769340Y462728I4374J-8819D01*
G02X769906Y462905I3220J-9303D01*
G02X770321Y463011I2643J-9483D01*
G03X772011Y463711I0J2390D01*
G01X772300Y464000D01*
G02X773724Y464590I1424J-1424D01*
G01X780514D01*
G01X727959Y470223D02*
X728483Y469698D01*
X730500Y467681D01*
G03X733539Y466422I3039J3039D01*
G01X733869D01*
Y466423D01*
X734853D01*
X735262Y466014D01*
X736253D01*
X736662Y466423D01*
X737653D01*
X738062Y466014D01*
X739053D01*
X739462Y466423D01*
X740453D01*
X740862Y466014D01*
X741853D01*
X742262Y466423D01*
X743253D01*
X743662Y466014D01*
X744653D01*
X745062Y466423D01*
X746053D01*
X746462Y466014D01*
X747453D01*
X747862Y466423D01*
X754299D01*
G03X759974Y468772I2J8025D01*
G01X760868Y469667D01*
X766854Y475653D01*
Y475654D01*
G02X769675Y477378I4981J-4981D01*
G01X771747D01*
G02X772476Y477076I0J-1031D01*
G03X774108Y476400I1632J1632D01*
G01X780514D01*
G01X732109Y474573D02*
X730735Y473200D01*
G03X730203Y471914I1286J-1285D01*
G01Y470511D01*
G03X730693Y469328I1673J0D01*
G01X731420Y468601D01*
G03X733617Y467723I2121J2119D01*
G01X733869D01*
Y467722D01*
G03X733870Y467723I-2358J2359D01*
G01X754299D01*
G03X759054Y469692I1J6724D01*
G01X759948Y470587D01*
X765934Y476573D01*
G02X769276Y478615I5900J-5900D01*
G02X769784Y478761I2558J-7942D01*
G01X771217D01*
G03X771835Y479017I0J874D01*
G01X772559Y479741D01*
G02X773993Y480335I1434J-1434D01*
G01X780514D01*
G01X719709Y462073D02*
Y461908D01*
X720452Y461164D01*
X725202Y456414D01*
X725203Y456415D01*
G03X728465Y455064I3261J3261D01*
G01X732543D01*
G02X735191Y453967I0J-3745D01*
G01X723809Y466173D02*
X722676Y465040D01*
X722215Y464578D01*
G03X721753Y463464I1114J-1115D01*
G01Y462225D01*
G03X722122Y461334I1260J0D01*
G01X726122Y457334D01*
G03X728464Y456364I2342J2342D01*
G01X733292D01*
G03X735231Y457167I0J2742D01*
G01X740309Y482873D02*
X739462Y482026D01*
G03X738402Y479467I2559J-2559D01*
G01Y479112D01*
G03X738963Y477758I1915J0D01*
G01X738964Y477757D01*
G03X739331Y477416I4582J4563D01*
G01X739332Y477417D01*
G03X742622Y475928I4205J4912D01*
G03X743533Y475863I915J6402D01*
G03X743535Y475864I-2883J5768D01*
G01X745578D01*
G03X746845Y476389I0J1792D01*
G01X736259Y478623D02*
X738048Y476834D01*
G03X741535Y474825I5480J5480D01*
G03X742439Y474641I1998J7505D01*
G03X743534Y474564I1091J7690D01*
G01X744900D01*
G02X745873Y474161I0J-1376D01*
G01X746845Y473189D01*
G01X736209Y478673D02*
X736259Y478623D01*
G01X715509Y454473D02*
G03X715933Y453448I1449J-1D01*
G01X716516Y452866D01*
X717993Y451389D01*
G01X727909Y466773D02*
X728919D01*
G02X729699Y466450I0J-1103D01*
G01X731751Y464398D01*
G01X732109Y471073D02*
X732422D01*
G02X735259Y469898I0J-4012D01*
G01X721445Y455789D02*
X720002Y457232D01*
G02X719709Y457939I706J707D01*
G01Y458573D01*
G01X723809Y462673D02*
G02X725544Y461955I1J-2453D01*
G01X726589Y460909D01*
G01X743520Y478297D02*
G03X740922Y479373I-2598J-2598D01*
G01X740309D01*
G01X736209Y475173D02*
X736361D01*
X738745Y472789D01*
G01X751965Y522097D02*
X752040D01*
X752966Y523023D01*
X756425D01*
X760600Y518848D01*
X763015D01*
X763510Y518353D01*
G01X780514Y511830D02*
X768418D01*
X768405Y511817D01*
X768383D01*
X763552Y516648D01*
Y518311D01*
X763510Y518353D01*
G01X747886Y522097D02*
X748099D01*
X750899Y524897D01*
X757551D01*
X758389Y524059D01*
X758641D01*
G01X780514Y515770D02*
X769415D01*
X761126Y524059D01*
X758641D01*
G01X780514Y503960D02*
X761015D01*
G01X757848Y513543D02*
X759520Y511871D01*
Y505455D01*
X761015Y503960D01*
G01X750750Y546500D02*
X754600D01*
X754800Y546300D01*
G01X780514Y551200D02*
X765182D01*
X760282Y546300D01*
X754800D01*
G01X780514Y539390D02*
X764507D01*
X757714Y532597D01*
X742400D01*
G01D02*
X741597D01*
X728600Y519600D01*
X725100D01*
G01X741600Y541600D02*
X746500Y546500D01*
X747250D01*
G01X736000Y539500D02*
Y537954D01*
X726800Y528754D01*
Y527400D01*
G01X736000Y539500D02*
Y539700D01*
X746000Y549700D01*
G01X723538Y526440D02*
Y528238D01*
X733750Y538450D01*
Y540744D01*
X738627Y545621D01*
G01X742607Y549481D02*
X742487D01*
X738627Y545621D01*
G01X780514Y519705D02*
X767743D01*
X760951Y526497D01*
X747771D01*
X746951Y525677D01*
G01X744073Y522097D02*
Y522117D01*
X746951Y524995D01*
Y525677D01*
G01X752515Y514433D02*
X754385Y516303D01*
X755862D01*
G01D02*
X761634D01*
X770042Y507895D01*
X780514D01*
G01X756272Y534995D02*
Y535103D01*
X760911Y539742D01*
G01X780514Y543330D02*
X772830D01*
X771200Y541700D01*
X762869D01*
X760911Y539742D01*
G01X763000Y490800D02*
X760400D01*
X759100Y489500D01*
G01X752950Y551800D02*
X759956D01*
X761000Y552844D01*
G01X780514Y555140D02*
X772260D01*
X771400Y556000D01*
X764156D01*
X761000Y552844D01*
G01X752950Y555900D02*
X757000D01*
G01X780514Y559075D02*
X772575D01*
X771400Y557900D01*
X762200D01*
X760200Y555900D01*
X757000D01*
G01X749480Y569233D02*
X742567D01*
X742300Y569500D01*
G01X749579Y573387D02*
X740213D01*
X737400Y576200D01*
G01X766358Y564600D02*
X768600Y566842D01*
X772987D01*
X773095Y566950D01*
X780514D01*
G01Y563015D02*
X772515D01*
X770214Y560714D01*
X760515D01*
G01X753079Y573387D02*
X752980Y573288D01*
Y569233D01*
G01X753050Y577500D02*
X753079Y577471D01*
Y573387D01*
G01X752987Y560714D02*
X760515D01*
G01X752980Y569233D02*
Y560721D01*
X752987Y560714D01*
G01X758400Y568500D02*
X761500Y571600D01*
X767870D01*
X768585Y570885D01*
X780514D01*
G01X749550Y577500D02*
X743000D01*
X742600Y577100D01*
G01X724305Y770450D02*
X726633Y768122D01*
X726932D01*
X753554Y741500D01*
X773400D01*
X774721Y740179D01*
X780514D01*
G01X723678Y774016D02*
X723947D01*
X753849Y744114D01*
X780514D01*
G01X727477Y775212D02*
Y775128D01*
X754551Y748054D01*
X780514D01*
G01X724733Y779559D02*
X729826D01*
X757396Y751989D01*
X780514D01*
G01X730028Y782297D02*
X730750Y781575D01*
X730785D01*
X756431Y755929D01*
X780514D01*
G01X724859Y784497D02*
X725259Y784097D01*
X730774D01*
X755007Y759864D01*
X780514D01*
G01X729988Y787114D02*
X731405Y785697D01*
X731437D01*
X753335Y763799D01*
X780514D01*
G01X716698Y771516D02*
X723239D01*
X724305Y770450D01*
G01X716698Y774016D02*
X723678D01*
G01X716698Y776516D02*
X726173D01*
X727477Y775212D01*
G01X716698Y779016D02*
X724190D01*
X724733Y779559D01*
G01X716698Y781516D02*
X729247D01*
X730028Y782297D01*
G01X716698Y784016D02*
X724378D01*
X724859Y784497D01*
G01X716698Y786516D02*
X729390D01*
X729988Y787114D01*
G01X716698Y789016D02*
X725193D01*
X725239Y788970D01*
G01D02*
X730678D01*
X751909Y767739D01*
X780514D01*
G01X716698Y791516D02*
X729386D01*
X729486Y791416D01*
G01D02*
X730600D01*
X750342Y771674D01*
X780514D01*
G01X716698Y794016D02*
X724883D01*
X725407Y794540D01*
G01D02*
X729739D01*
X748665Y775614D01*
X780514D01*
G01X716012Y829419D02*
X719487D01*
X722443Y826463D01*
G01D02*
Y805651D01*
X750294Y777800D01*
X772900D01*
X774649Y779549D01*
X780514D01*
G01X716012Y831919D02*
X719766D01*
X721704Y829981D01*
G01D02*
Y829748D01*
X724243Y827209D01*
Y826445D01*
X758088Y792600D01*
X771500D01*
X772741Y791359D01*
X780514D01*
G01X716012Y834419D02*
X720741D01*
X723906Y831254D01*
X724858D01*
G01D02*
X725083Y831029D01*
X725198D01*
X726443Y829784D01*
Y827561D01*
X746810Y807194D01*
X751523D01*
X763418Y795299D01*
X780514D01*
G01X716012Y836919D02*
X721715D01*
X723777Y834857D01*
X723801D01*
G01D02*
X723813Y834845D01*
X724825D01*
X750876Y808794D01*
X752186D01*
X761746Y799234D01*
X780514D01*
G01X716012Y839419D02*
X721478D01*
X723769Y837128D01*
X726332D01*
G01D02*
X736902Y826558D01*
X738283D01*
X761672Y803169D01*
X780514D01*
G01X724093Y840187D02*
X726783D01*
X738812Y828158D01*
X739075D01*
X760124Y807109D01*
X780514D01*
G01Y814984D02*
X770884D01*
X766500Y810600D01*
X761181D01*
X737062Y834719D01*
Y845433D01*
G01X780514Y811044D02*
X770644D01*
X768400Y808800D01*
X760717D01*
X733171Y836346D01*
X733170D01*
X733066Y836450D01*
G01X733796Y854172D02*
Y837180D01*
X733066Y836450D01*
G01X725750Y853200D02*
X725741Y853209D01*
Y857331D01*
G01D02*
X724759D01*
X718263Y863827D01*
G01X716012Y841919D02*
X722361D01*
X724093Y840187D01*
G01X726776Y842277D02*
X726667D01*
X724525Y844419D01*
X716012D01*
G01X729241Y857331D02*
X735371D01*
X737062Y855640D01*
Y845433D01*
G54D101*
G01X-755164Y-252763D02*
Y-235263D01*
G01X-746868D02*
X-755164Y-246055D01*
G01X-745558Y-252763D02*
X-751453Y-241097D01*
G01X-737883Y-252763D02*
Y-235263D01*
X-727839Y-252763D01*
Y-235263D01*
G01X-715361Y-252763D02*
X-717108Y-252471D01*
X-718636Y-251305D01*
X-719946Y-249555D01*
X-720820Y-247513D01*
X-721256Y-245180D01*
Y-242846D01*
X-720820Y-240513D01*
X-719946Y-238471D01*
X-718636Y-236722D01*
X-717108Y-235555D01*
X-715361Y-235263D01*
X-713615Y-235555D01*
X-712086Y-236722D01*
X-710776Y-238471D01*
X-709902Y-240513D01*
X-709466Y-242846D01*
Y-245180D01*
X-709902Y-247513D01*
X-710776Y-249555D01*
X-712086Y-251305D01*
X-713615Y-252471D01*
X-715361Y-252763D01*
G01X-702446D02*
X-693276Y-235263D01*
G01X-702446D02*
X-693276Y-252763D01*
G01X-658494D02*
X-667228D01*
Y-235263D01*
X-658494D01*
G01X-661988Y-243721D02*
X-667228D01*
G01X-649946Y-252763D02*
X-640776Y-235263D01*
G01X-649946D02*
X-640776Y-252763D01*
G01X-632228D02*
Y-235263D01*
X-626988D01*
X-625241Y-236138D01*
X-623931Y-238180D01*
X-623494Y-240513D01*
X-623931Y-242846D01*
X-625023Y-244596D01*
X-626988Y-245472D01*
X-632228D01*
G01X-615820Y-252763D02*
X-610361Y-235263D01*
X-604902Y-252763D01*
G01X-606868Y-246638D02*
X-613855D01*
G01X-597883Y-252763D02*
Y-235263D01*
X-587839Y-252763D01*
Y-235263D01*
G01X-580164Y-252763D02*
Y-235263D01*
X-575798D01*
X-574051Y-236138D01*
X-572741Y-237305D01*
X-571649Y-239054D01*
X-570776Y-241097D01*
X-570558Y-244013D01*
X-570776Y-246930D01*
X-571649Y-248972D01*
X-572741Y-250722D01*
X-574051Y-251888D01*
X-575798Y-252763D01*
X-580164D01*
G01X-553494D02*
X-562228D01*
Y-235263D01*
X-553494D01*
G01X-556988Y-243721D02*
X-562228D01*
G01X-544728Y-252763D02*
Y-235263D01*
X-539269D01*
X-537523Y-236138D01*
X-536431Y-237305D01*
X-535994Y-239638D01*
X-536431Y-241972D01*
X-537741Y-243430D01*
X-539269Y-244305D01*
X-544728D01*
G01X-539269D02*
X-535994Y-252763D01*
G01X-503615Y-243430D02*
X-502741Y-242555D01*
X-502086Y-241097D01*
X-501649Y-239054D01*
X-502086Y-237305D01*
X-502959Y-236138D01*
X-504488Y-235263D01*
X-510383D01*
Y-252763D01*
X-503178D01*
X-501649Y-251597D01*
X-500776Y-249846D01*
X-500339Y-247805D01*
X-500776Y-245763D01*
X-502086Y-244013D01*
X-503615Y-243430D01*
X-510383D01*
G01X-487861Y-252763D02*
X-489608Y-252471D01*
X-491136Y-251305D01*
X-492446Y-249555D01*
X-493320Y-247513D01*
X-493756Y-245180D01*
Y-242846D01*
X-493320Y-240513D01*
X-492446Y-238471D01*
X-491136Y-236722D01*
X-489608Y-235555D01*
X-487861Y-235263D01*
X-486115Y-235555D01*
X-484586Y-236722D01*
X-483276Y-238471D01*
X-482402Y-240513D01*
X-481966Y-242846D01*
Y-245180D01*
X-482402Y-247513D01*
X-483276Y-249555D01*
X-484586Y-251305D01*
X-486115Y-252471D01*
X-487861Y-252763D01*
G01X-475820D02*
X-470361Y-235263D01*
X-464902Y-252763D01*
G01X-466868Y-246638D02*
X-473855D01*
G01X-457228Y-252763D02*
Y-235263D01*
X-451769D01*
X-450023Y-236138D01*
X-448931Y-237305D01*
X-448494Y-239638D01*
X-448931Y-241972D01*
X-450241Y-243430D01*
X-451769Y-244305D01*
X-457228D01*
G01X-451769D02*
X-448494Y-252763D01*
G01X-440164D02*
Y-235263D01*
X-435798D01*
X-434051Y-236138D01*
X-432741Y-237305D01*
X-431649Y-239054D01*
X-430776Y-241097D01*
X-430558Y-244013D01*
X-430776Y-246930D01*
X-431649Y-248972D01*
X-432741Y-250722D01*
X-434051Y-251888D01*
X-435798Y-252763D01*
X-440164D01*
G01X-633538Y-207763D02*
Y-190263D01*
X-627861Y-204846D01*
X-622184Y-190263D01*
Y-207763D01*
G01X-610361D02*
X-611671Y-207471D01*
X-612981Y-206305D01*
X-613855Y-204263D01*
X-614291Y-201930D01*
X-613855Y-199596D01*
X-612981Y-197555D01*
X-611671Y-196388D01*
X-610361Y-196097D01*
X-609051Y-196388D01*
X-607741Y-197555D01*
X-606868Y-199596D01*
X-606649Y-201930D01*
X-606868Y-204263D01*
X-607741Y-206305D01*
X-609051Y-207471D01*
X-610361Y-207763D01*
G01X-588931Y-190263D02*
Y-207763D01*
G01Y-205139D02*
X-589804Y-206597D01*
X-591115Y-207471D01*
X-592643Y-207763D01*
X-594389Y-207180D01*
X-595699Y-205722D01*
X-596573Y-203972D01*
X-596791Y-201930D01*
X-596573Y-199888D01*
X-595699Y-198138D01*
X-594389Y-196680D01*
X-592643Y-196097D01*
X-591115Y-196388D01*
X-590023Y-196972D01*
X-588931Y-198138D01*
G01X-578636Y-199888D02*
X-571649D01*
X-572304Y-197846D01*
X-573396Y-196680D01*
X-574924Y-196097D01*
X-576453Y-196388D01*
X-577763Y-197263D01*
X-578636Y-199305D01*
X-579073Y-201055D01*
Y-202805D01*
X-578636Y-204555D01*
X-577544Y-206305D01*
X-576234Y-207471D01*
X-574706Y-207763D01*
X-573178Y-207180D01*
X-571649Y-205430D01*
G01X-557861Y-207763D02*
Y-190263D01*
G01X-380161Y-252763D02*
Y-235263D01*
X-382781Y-238763D01*
G01Y-252763D02*
X-377541D01*
G01X-366809Y-238180D02*
X-365499Y-236430D01*
X-363971Y-235555D01*
X-362224Y-235263D01*
X-360041Y-235846D01*
X-358513Y-237305D01*
X-358076Y-239054D01*
X-358294Y-240805D01*
X-359168Y-242263D01*
X-363534Y-245180D01*
X-365499Y-247221D01*
X-366809Y-250139D01*
X-367246Y-252763D01*
X-358076D01*
G01X-345161Y-235263D02*
X-346908Y-235846D01*
X-348218Y-237305D01*
X-349091Y-239054D01*
X-349746Y-241388D01*
X-349964Y-244013D01*
X-349746Y-246638D01*
X-349091Y-248972D01*
X-348218Y-250722D01*
X-346908Y-252180D01*
X-345161Y-252763D01*
X-343415Y-252180D01*
X-342104Y-250722D01*
X-341231Y-248972D01*
X-340576Y-246638D01*
X-340358Y-244013D01*
X-340576Y-241388D01*
X-341231Y-239054D01*
X-342104Y-237305D01*
X-343415Y-235846D01*
X-345161Y-235263D01*
G01X-327661D02*
X-329408Y-235846D01*
X-330718Y-237305D01*
X-331591Y-239054D01*
X-332246Y-241388D01*
X-332464Y-244013D01*
X-332246Y-246638D01*
X-331591Y-248972D01*
X-330718Y-250722D01*
X-329408Y-252180D01*
X-327661Y-252763D01*
X-325915Y-252180D01*
X-324604Y-250722D01*
X-323731Y-248972D01*
X-323076Y-246638D01*
X-322858Y-244013D01*
X-323076Y-241388D01*
X-323731Y-239054D01*
X-324604Y-237305D01*
X-325915Y-235846D01*
X-327661Y-235263D01*
G01X-307541Y-252763D02*
Y-235263D01*
X-315620Y-247805D01*
X-304702D01*
G01X-393278Y-207763D02*
Y-190263D01*
X-388038D01*
X-386291Y-191138D01*
X-384981Y-193180D01*
X-384544Y-195513D01*
X-384981Y-197846D01*
X-386073Y-199596D01*
X-388038Y-200472D01*
X-393278D01*
G01X-366608Y-191722D02*
X-367918Y-190846D01*
X-369446Y-190263D01*
X-371193D01*
X-373158Y-191138D01*
X-374686Y-192596D01*
X-375778Y-194347D01*
X-376651Y-197263D01*
X-376870Y-199888D01*
X-376433Y-202513D01*
X-375778Y-204263D01*
X-374468Y-206013D01*
X-372939Y-207180D01*
X-371411Y-207763D01*
X-369883D01*
X-368354Y-207180D01*
X-367044Y-206305D01*
X-365952Y-205139D01*
G01X-352165Y-198430D02*
X-351291Y-197555D01*
X-350636Y-196097D01*
X-350199Y-194054D01*
X-350636Y-192305D01*
X-351509Y-191138D01*
X-353038Y-190263D01*
X-358933D01*
Y-207763D01*
X-351728D01*
X-350199Y-206597D01*
X-349326Y-204846D01*
X-348889Y-202805D01*
X-349326Y-200763D01*
X-350636Y-199013D01*
X-352165Y-198430D01*
X-358933D01*
G01X-342961Y-213596D02*
X-329861D01*
G01X-323933Y-207763D02*
Y-190263D01*
X-313889Y-207763D01*
Y-190263D01*
G01X-301411Y-207763D02*
X-303158Y-207471D01*
X-304686Y-206305D01*
X-305996Y-204555D01*
X-306870Y-202513D01*
X-307306Y-200180D01*
Y-197846D01*
X-306870Y-195513D01*
X-305996Y-193471D01*
X-304686Y-191722D01*
X-303158Y-190555D01*
X-301411Y-190263D01*
X-299665Y-190555D01*
X-298136Y-191722D01*
X-296826Y-193471D01*
X-295952Y-195513D01*
X-295516Y-197846D01*
Y-200180D01*
X-295952Y-202513D01*
X-296826Y-204555D01*
X-298136Y-206305D01*
X-299665Y-207471D01*
X-301411Y-207763D01*
G01X-218861Y-252763D02*
Y-235263D01*
X-221481Y-238763D01*
G01Y-252763D02*
X-216241D01*
G01X-250570Y-190263D02*
X-245111Y-207763D01*
X-239652Y-190263D01*
G01X-223244Y-207763D02*
X-231978D01*
Y-190263D01*
X-223244D01*
G01X-226738Y-198721D02*
X-231978D01*
G01X-214478Y-207763D02*
Y-190263D01*
X-209019D01*
X-207273Y-191138D01*
X-206181Y-192305D01*
X-205744Y-194638D01*
X-206181Y-196972D01*
X-207491Y-198430D01*
X-209019Y-199305D01*
X-214478D01*
G01X-209019D02*
X-205744Y-207763D01*
G01X-192611Y-208346D02*
X-193048Y-208055D01*
Y-207471D01*
X-192611Y-207180D01*
X-192174Y-207471D01*
Y-208055D01*
X-192611Y-208346D01*
G01X-90778Y-235263D02*
Y-252763D01*
X-82044D01*
G01X-68911D02*
Y-235263D01*
X-71531Y-238763D01*
G01Y-252763D02*
X-66291D01*
G01X-125778Y-190263D02*
Y-207763D01*
X-117044D01*
G01X-99981D02*
Y-196097D01*
G01Y-198138D02*
X-100854Y-196972D01*
X-102165Y-196388D01*
X-103693Y-196097D01*
X-105221Y-196680D01*
X-106531Y-197846D01*
X-107405Y-199596D01*
X-107841Y-201930D01*
X-107405Y-204263D01*
X-106531Y-206013D01*
X-105221Y-207180D01*
X-103693Y-207763D01*
X-102165Y-207471D01*
X-100854Y-206597D01*
X-99981Y-205430D01*
G01X-90996Y-213013D02*
X-89686Y-213596D01*
X-87939Y-213013D01*
X-86848Y-211847D01*
X-85974Y-210388D01*
X-84665Y-205722D01*
X-81826Y-196097D01*
G01X-88813D02*
X-84665Y-205722D01*
G01X-72186Y-199888D02*
X-65199D01*
X-65854Y-197846D01*
X-66946Y-196680D01*
X-68474Y-196097D01*
X-70003Y-196388D01*
X-71313Y-197263D01*
X-72186Y-199305D01*
X-72623Y-201055D01*
Y-202805D01*
X-72186Y-204555D01*
X-71094Y-206305D01*
X-69784Y-207471D01*
X-68256Y-207763D01*
X-66728Y-207180D01*
X-65199Y-205430D01*
G01X-54468Y-207763D02*
Y-196097D01*
G01Y-198430D02*
X-53376Y-197263D01*
X-52284Y-196388D01*
X-50756Y-196097D01*
X-49665Y-196388D01*
X-48354Y-197263D01*
G01X-37186Y-205722D02*
X-36094Y-206888D01*
X-34566Y-207763D01*
X-33256D01*
X-31946Y-207180D01*
X-31073Y-206305D01*
X-30636Y-205139D01*
X-30854Y-203388D01*
X-31728Y-202513D01*
X-35658Y-200763D01*
X-36531Y-198721D01*
X-36094Y-197263D01*
X-35221Y-196388D01*
X-33911Y-196097D01*
X-32601Y-196388D01*
X-31291Y-197263D01*
G01X51772Y-235263D02*
Y-252763D01*
X60506D01*
G01X68836Y-235263D02*
Y-247805D01*
X69709Y-250430D01*
X71456Y-252180D01*
X73639Y-252763D01*
X75822Y-252180D01*
X77569Y-250430D01*
X78442Y-247805D01*
Y-235263D01*
G01X95942Y-236722D02*
X94632Y-235846D01*
X93104Y-235263D01*
X91357D01*
X89392Y-236138D01*
X87864Y-237596D01*
X86772Y-239347D01*
X85899Y-242263D01*
X85680Y-244888D01*
X86117Y-247513D01*
X86772Y-249263D01*
X88082Y-251013D01*
X89611Y-252180D01*
X91139Y-252763D01*
X92667D01*
X94196Y-252180D01*
X95506Y-251305D01*
X96598Y-250139D01*
G01X103836Y-252763D02*
Y-235263D01*
G01X112132D02*
X103836Y-246055D01*
G01X113442Y-252763D02*
X107547Y-241097D01*
G01X126139Y-252763D02*
Y-244888D01*
X121772Y-235263D01*
G01X130506D02*
X126139Y-244888D01*
G01X25086Y-207763D02*
Y-190263D01*
X29452D01*
X31199Y-191138D01*
X32509Y-192305D01*
X33601Y-194054D01*
X34474Y-196097D01*
X34692Y-199013D01*
X34474Y-201930D01*
X33601Y-203972D01*
X32509Y-205722D01*
X31199Y-206888D01*
X29452Y-207763D01*
X25086D01*
G01X44114Y-199888D02*
X51101D01*
X50446Y-197846D01*
X49354Y-196680D01*
X47826Y-196097D01*
X46297Y-196388D01*
X44987Y-197263D01*
X44114Y-199305D01*
X43677Y-201055D01*
Y-202805D01*
X44114Y-204555D01*
X45206Y-206305D01*
X46516Y-207471D01*
X48044Y-207763D01*
X49572Y-207180D01*
X51101Y-205430D01*
G01X61614Y-205722D02*
X62706Y-206888D01*
X64234Y-207763D01*
X65544D01*
X66854Y-207180D01*
X67727Y-206305D01*
X68164Y-205139D01*
X67946Y-203388D01*
X67072Y-202513D01*
X63142Y-200763D01*
X62269Y-198721D01*
X62706Y-197263D01*
X63579Y-196388D01*
X64889Y-196097D01*
X66199Y-196388D01*
X67509Y-197263D01*
G01X82389Y-196097D02*
Y-207763D01*
G01Y-191430D02*
X81952Y-191138D01*
Y-190555D01*
X82389Y-190263D01*
X82826Y-190555D01*
Y-191138D01*
X82389Y-191430D01*
G01X96832Y-212138D02*
X98361Y-213305D01*
X100107Y-213596D01*
X101635Y-213305D01*
X102946Y-211847D01*
X103819Y-209805D01*
Y-196097D01*
G01Y-198430D02*
X102946Y-197263D01*
X101635Y-196388D01*
X100107Y-196097D01*
X98361Y-196680D01*
X97269Y-197846D01*
X96395Y-199888D01*
X95959Y-201930D01*
X96177Y-203680D01*
X97051Y-205722D01*
X98361Y-207180D01*
X100107Y-207763D01*
X101417Y-207471D01*
X102946Y-206305D01*
X103819Y-205139D01*
G01X113677Y-207763D02*
Y-196097D01*
G01Y-199013D02*
X114551Y-197555D01*
X115861Y-196388D01*
X117607Y-196097D01*
X119135Y-196388D01*
X120446Y-197555D01*
X121101Y-199596D01*
Y-207763D01*
G01X131614Y-199888D02*
X138601D01*
X137946Y-197846D01*
X136854Y-196680D01*
X135326Y-196097D01*
X133797Y-196388D01*
X132487Y-197263D01*
X131614Y-199305D01*
X131177Y-201055D01*
Y-202805D01*
X131614Y-204555D01*
X132706Y-206305D01*
X134016Y-207471D01*
X135544Y-207763D01*
X137072Y-207180D01*
X138601Y-205430D01*
G01X149332Y-207763D02*
Y-196097D01*
G01Y-198430D02*
X150424Y-197263D01*
X151516Y-196388D01*
X153044Y-196097D01*
X154135Y-196388D01*
X155446Y-197263D01*
G01X196089Y-252763D02*
Y-235263D01*
X193469Y-238763D01*
G01Y-252763D02*
X198709D01*
G01X213589Y-235263D02*
X211842Y-235846D01*
X210532Y-237305D01*
X209659Y-239054D01*
X209004Y-241388D01*
X208786Y-244013D01*
X209004Y-246638D01*
X209659Y-248972D01*
X210532Y-250722D01*
X211842Y-252180D01*
X213589Y-252763D01*
X215335Y-252180D01*
X216646Y-250722D01*
X217519Y-248972D01*
X218174Y-246638D01*
X218392Y-244013D01*
X218174Y-241388D01*
X217519Y-239054D01*
X216646Y-237305D01*
X215335Y-235846D01*
X213589Y-235263D01*
G01X227159Y-253346D02*
X235019Y-235263D01*
G01X248589Y-252763D02*
Y-235263D01*
X245969Y-238763D01*
G01Y-252763D02*
X251209D01*
G01X261941Y-245472D02*
X263469Y-243430D01*
X264779Y-242263D01*
X266526Y-241680D01*
X268054Y-242263D01*
X269146Y-243430D01*
X270019Y-245180D01*
X270237Y-247221D01*
X270019Y-248972D01*
X269146Y-250722D01*
X267835Y-252180D01*
X266307Y-252763D01*
X264561Y-252180D01*
X263032Y-250430D01*
X262159Y-247805D01*
X261941Y-244888D01*
X262377Y-241097D01*
X263032Y-239054D01*
X264124Y-237013D01*
X265652Y-235555D01*
X267181Y-235263D01*
X268709Y-235846D01*
X269801Y-237305D01*
G01X279659Y-253346D02*
X287519Y-235263D01*
G01X296941Y-238180D02*
X298251Y-236430D01*
X299779Y-235555D01*
X301526Y-235263D01*
X303709Y-235846D01*
X305237Y-237305D01*
X305674Y-239054D01*
X305456Y-240805D01*
X304582Y-242263D01*
X300216Y-245180D01*
X298251Y-247221D01*
X296941Y-250139D01*
X296504Y-252763D01*
X305674D01*
G01X318589Y-235263D02*
X316842Y-235846D01*
X315532Y-237305D01*
X314659Y-239054D01*
X314004Y-241388D01*
X313786Y-244013D01*
X314004Y-246638D01*
X314659Y-248972D01*
X315532Y-250722D01*
X316842Y-252180D01*
X318589Y-252763D01*
X320335Y-252180D01*
X321646Y-250722D01*
X322519Y-248972D01*
X323174Y-246638D01*
X323392Y-244013D01*
X323174Y-241388D01*
X322519Y-239054D01*
X321646Y-237305D01*
X320335Y-235846D01*
X318589Y-235263D01*
G01X336089Y-252763D02*
Y-235263D01*
X333469Y-238763D01*
G01Y-252763D02*
X338709D01*
G01X349441Y-238180D02*
X350751Y-236430D01*
X352279Y-235555D01*
X354026Y-235263D01*
X356209Y-235846D01*
X357737Y-237305D01*
X358174Y-239054D01*
X357956Y-240805D01*
X357082Y-242263D01*
X352716Y-245180D01*
X350751Y-247221D01*
X349441Y-250139D01*
X349004Y-252763D01*
X358174D01*
G01X243786Y-207763D02*
Y-190263D01*
X248152D01*
X249899Y-191138D01*
X251209Y-192305D01*
X252301Y-194054D01*
X253174Y-196097D01*
X253392Y-199013D01*
X253174Y-201930D01*
X252301Y-203972D01*
X251209Y-205722D01*
X249899Y-206888D01*
X248152Y-207763D01*
X243786D01*
G01X270019D02*
Y-196097D01*
G01Y-198138D02*
X269146Y-196972D01*
X267835Y-196388D01*
X266307Y-196097D01*
X264779Y-196680D01*
X263469Y-197846D01*
X262595Y-199596D01*
X262159Y-201930D01*
X262595Y-204263D01*
X263469Y-206013D01*
X264779Y-207180D01*
X266307Y-207763D01*
X267835Y-207471D01*
X269146Y-206597D01*
X270019Y-205430D01*
G01X283589Y-190263D02*
Y-207763D01*
G01X280532Y-196097D02*
X286646D01*
G01X297814Y-199888D02*
X304801D01*
X304146Y-197846D01*
X303054Y-196680D01*
X301526Y-196097D01*
X299997Y-196388D01*
X298687Y-197263D01*
X297814Y-199305D01*
X297377Y-201055D01*
Y-202805D01*
X297814Y-204555D01*
X298906Y-206305D01*
X300216Y-207471D01*
X301744Y-207763D01*
X303272Y-207180D01*
X304801Y-205430D01*
G01X90359Y469275D02*
X90498D01*
X92523Y467250D01*
G01X98682Y461441D02*
Y461091D01*
X100397Y459376D01*
G01X223600Y456200D02*
X224200Y455600D01*
X228750D01*
X229650Y454700D01*
G01D02*
X230250Y454100D01*
Y448600D01*
G01X226000Y458700D02*
X227000Y457700D01*
X232000D01*
X233150Y456550D01*
Y454700D01*
G01D02*
X232750Y454300D01*
Y448600D01*
G54D10*
G01X70200Y199300D02*
X70699Y198801D01*
Y198458D01*
X71660Y197497D01*
Y193550D01*
G01X62439Y413744D02*
X62763Y414068D01*
X66544D01*
X68544Y416068D01*
X68901D01*
G01X52151Y456887D02*
X52603Y457339D01*
X66553D01*
X66903Y457689D01*
G01X62798Y461555D02*
X62940Y461413D01*
X66229D01*
X68266Y459376D01*
X68901D01*
G01X214172Y101900D02*
Y110228D01*
X201400Y123000D01*
X144300D01*
X112000Y90700D01*
X110000D01*
G01D02*
X107800Y88500D01*
Y86611D01*
X107783D01*
G01X83800Y188800D02*
X85348Y190348D01*
X86397D01*
X87300Y191251D01*
X91599D01*
G01X83488Y184954D02*
Y188488D01*
X83800Y188800D01*
G01X115091Y202800D02*
X111482D01*
G01D02*
Y201721D01*
X114203Y199000D01*
X115091D01*
G01X98991Y203600D02*
X102991D01*
X103091Y203500D01*
G01D02*
Y198657D01*
X104592Y197156D01*
X107899D01*
G01X98741Y207700D02*
Y203850D01*
X98991Y203600D01*
G01X106591Y203500D02*
X111314Y198777D01*
Y198756D01*
X111899Y198171D01*
Y196141D01*
X110949Y195191D01*
X107899D01*
G01X104741Y207700D02*
X106591Y205850D01*
Y203500D01*
G01X113815Y194333D02*
X112703Y193221D01*
X107899D01*
G01X117291Y194500D02*
X113982D01*
X113815Y194333D01*
G01X129310Y204175D02*
Y200328D01*
X127982Y199000D01*
X122400D01*
G01D02*
X118591D01*
G01D02*
Y197000D01*
X120791Y194800D01*
Y194500D01*
G01X80750Y199800D02*
X81150Y200200D01*
X84100D01*
X84600Y199700D01*
G01X91599Y195191D02*
X85003D01*
X84296Y195898D01*
G01D02*
X84600Y196202D01*
Y199700D01*
G01X91599Y193221D02*
X85119D01*
X84296Y192398D01*
G01D02*
X80685D01*
G01X93130Y150935D02*
Y154797D01*
X93303Y154970D01*
G01X95100Y215200D02*
X95717Y214583D01*
X95749D01*
X97732Y212600D01*
X99335D01*
X99525Y212410D01*
G01D02*
Y208484D01*
X98741Y207700D01*
G01X109100Y214300D02*
X107214Y212414D01*
X104382D01*
G01D02*
Y208059D01*
X104741Y207700D01*
G01X104382Y218414D02*
X106768Y220800D01*
X116500D01*
X126400Y210900D01*
X149700D01*
X152400Y213600D01*
Y221700D01*
X153931Y223231D01*
X162963D01*
G01X115121Y206661D02*
X110835D01*
X110610Y206436D01*
G01X99525Y218410D02*
Y220925D01*
X101700Y223100D01*
X118200D01*
X128000Y213300D01*
X148500D01*
X149900Y214700D01*
Y221500D01*
X148169Y223231D01*
X140847D01*
G01X126066Y472976D02*
Y471984D01*
X126057Y471975D01*
Y469287D01*
G01X220131Y58163D02*
X219115Y59179D01*
Y62233D01*
G01X225231Y65070D02*
X221952D01*
X219115Y62233D01*
G01X201315Y81383D02*
X198517D01*
X197900Y82000D01*
G01D02*
X197515Y82385D01*
Y91533D01*
X199771Y93789D01*
X202970D01*
G01X208612Y81480D02*
X210680Y83548D01*
Y84396D01*
G01X214240Y98033D02*
X211427D01*
X210356Y99104D01*
G01D02*
Y109244D01*
X206144Y113456D01*
X203111D01*
G01X201614Y85481D02*
Y89932D01*
G01X204811Y81477D02*
Y82284D01*
X201614Y85481D01*
G01X212028Y93512D02*
Y92181D01*
X213247Y90962D01*
Y90961D01*
X214201Y90007D01*
X216447D01*
G01X158100Y166800D02*
X157524Y166224D01*
Y162725D01*
X158215Y162034D01*
X160359D01*
G01X153061Y168762D02*
X156138D01*
X158100Y166800D01*
G01X168084Y171855D02*
X170302Y169637D01*
Y165087D01*
G01X177087Y171983D02*
X172685D01*
G01D02*
X168212D01*
X168084Y171855D01*
G01X181200Y176300D02*
Y175776D01*
X177407Y171983D01*
X177087D01*
G01X174339Y156128D02*
X176872D01*
X178400Y154600D01*
G01X167015Y167633D02*
X166232Y166850D01*
X165550D01*
X164396Y165696D01*
Y165087D01*
G01X163113Y171759D02*
X163641D01*
X167015Y168385D01*
Y167633D01*
G01X163299Y176397D02*
X163113Y176211D01*
Y171759D01*
G01X155431Y176850D02*
X159346D01*
X159799Y176397D01*
G01D02*
Y176617D01*
X162839Y179657D01*
X163550D01*
G01X168084Y177855D02*
X170456Y175483D01*
X172685D01*
G01D02*
Y179064D01*
X172645Y179104D01*
G01X229613Y64948D02*
X225353D01*
X225231Y65070D01*
G01X242488Y88466D02*
X242061Y88039D01*
X235733D01*
G01X246640Y89833D02*
X245273Y88466D01*
X242488D01*
G01X249515Y394630D02*
X252970D01*
X253700Y393900D01*
G01X243222Y392396D02*
X244696D01*
X246930Y394630D01*
X249515D01*
G01X249759Y403106D02*
Y399406D01*
X249832Y399333D01*
G01D02*
X243765D01*
X243222Y399876D01*
G01X249759Y403106D02*
Y406641D01*
X248900Y407500D01*
G01X499500Y405382D02*
X504094D01*
G01X504027Y409425D02*
X501666D01*
X499767Y411324D01*
X499764D01*
G01X503981Y416969D02*
X500000D01*
G01X537200Y394350D02*
X538250D01*
X646800Y502900D01*
X709600D01*
X722000Y515300D01*
Y519600D01*
X722900Y520500D01*
Y520512D01*
X724188Y521800D01*
X724200D01*
X724400Y522000D01*
X727600D01*
X747133Y541533D01*
X747915D01*
G01X517041Y388700D02*
Y395041D01*
X518160Y396160D01*
X520900D01*
G01X517041Y388700D02*
Y383209D01*
X520250Y380000D01*
G01D02*
X526100D01*
X537200Y391100D01*
Y394350D01*
G01X536928Y411324D02*
X534827Y413425D01*
X530634D01*
G01X504094Y405382D02*
X504027Y405449D01*
Y409425D01*
G01X510634Y413425D02*
X506600D01*
X506100Y412925D01*
X504027D01*
G01D02*
Y416923D01*
X503981Y416969D01*
G01X662514Y528887D02*
X660066D01*
X656003Y532950D01*
X654800D01*
G01D02*
X650700D01*
G01D02*
Y536600D01*
G01X664700Y539750D02*
X664130Y540300D01*
X661300D01*
X660800Y539800D01*
G01X667139Y533512D02*
X666922Y533295D01*
X662653D01*
X660800Y535148D01*
Y539800D01*
G01X780514Y547265D02*
X764447D01*
X758715Y541533D01*
X747915D01*
X-1011811Y-15748D03*
Y940945D03*
X-59094Y277559D03*
X-7913D03*
X-33503Y269685D03*
X54724Y557087D03*
Y620079D03*
Y675197D03*
Y738189D03*
X144843Y798779D03*
Y812994D03*
Y874449D03*
Y860234D03*
X716535Y39370D03*
X775591Y-15748D03*
Y940944D03*
G54D20*
X43100Y106900D03*
X46863Y382383D03*
X65763Y374283D03*
X59384Y641101D03*
X84296Y195848D03*
X149031Y172300D03*
X115096Y190370D03*
X79922Y636086D03*
X80191Y651287D03*
X80653Y751104D03*
X80464Y768206D03*
X217113Y134260D03*
X172685Y175433D03*
X168353Y143690D03*
X185266Y485343D03*
X189415Y416933D03*
X225231Y65020D03*
X225002Y134216D03*
X231350Y217608D03*
X226428Y398441D03*
X222254Y398349D03*
X236637Y387093D03*
X241728Y367656D03*
X237455Y378755D03*
X246800Y440000D03*
X231108Y467537D03*
X226992Y467483D03*
X537200Y397800D03*
X657609Y474323D03*
X661709Y470223D03*
X674109Y457923D03*
X678509Y453723D03*
X654800Y532900D03*
X736209Y478623D03*
X740309Y482823D03*
X723809Y466123D03*
X719709Y462023D03*
G54D11*
X-944882Y-17185D03*
Y942382D03*
X43000Y354200D03*
X245200Y551000D03*
X708683Y-17218D03*
G54D21*
X48500Y93600D03*
X66863Y267083D03*
X59263D03*
X66363Y272683D03*
X66863Y258783D03*
X59263Y258883D03*
X66863Y254683D03*
X59263Y251483D03*
X67063Y250483D03*
Y246283D03*
X59146Y242114D03*
X66963Y242083D03*
X67063Y237683D03*
X66863Y262883D03*
X66801Y294778D03*
Y290678D03*
X58863Y285083D03*
X66496Y285730D03*
Y281630D03*
X58863Y276783D03*
X66363D03*
X50680Y373862D03*
X66222Y517540D03*
X55179Y521570D03*
X43855Y517250D03*
X77242Y521666D03*
X91241Y203800D03*
X118571Y206661D03*
X143553Y331742D03*
X132417Y335856D03*
X120955Y331729D03*
X132863Y517903D03*
X88362Y517603D03*
X99385Y521826D03*
X110607Y517857D03*
X121751Y522079D03*
X143912Y522038D03*
X206425Y98053D03*
X154552Y335814D03*
X176638Y344153D03*
X165585Y339913D03*
X209880Y356594D03*
X198838Y352449D03*
X187757Y348289D03*
X192966Y481243D03*
X177049Y517848D03*
X154874Y517879D03*
X165905Y522020D03*
X210263Y522003D03*
X199063Y517803D03*
X188063Y522003D03*
X221359Y106010D03*
X250115Y93933D03*
X250090Y89833D03*
X248046Y77735D03*
X248190Y102533D03*
X248052Y73668D03*
X227102Y214585D03*
X252553Y387029D03*
X221085Y363914D03*
X246097Y432409D03*
X238700Y482954D03*
X234562Y779010D03*
X234666Y783159D03*
X234621Y787335D03*
X285742Y794780D03*
X338146Y793055D03*
X353927Y792923D03*
X308899Y794862D03*
X319115Y795010D03*
X297576Y794808D03*
X490830Y532955D03*
X490838Y541335D03*
X490523Y549911D03*
X478687Y490049D03*
X460541Y490002D03*
X490899Y508498D03*
X490902Y512828D03*
X450818Y508324D03*
X508100Y389700D03*
X511734Y424179D03*
X528810Y531644D03*
X528788Y527470D03*
X711409Y453923D03*
X661009Y474323D03*
X665109Y470223D03*
X677509Y457923D03*
X681909Y453723D03*
X692400Y537000D03*
X732109Y474523D03*
X727909Y470223D03*
X715509Y458023D03*
X729191Y857331D03*
G54D30*
X47360Y172352D03*
X73400Y180800D03*
X106641Y203500D03*
X118641Y202800D03*
X148200Y233900D03*
X217790Y98033D03*
X203161Y113456D03*
X192763Y240983D03*
X192721Y244556D03*
X192763Y248183D03*
Y237383D03*
X188909Y421839D03*
X193066Y493343D03*
X253382Y399333D03*
X252641Y383206D03*
X245155Y375055D03*
X245130Y371576D03*
X249465Y363969D03*
X249428Y360456D03*
X241100Y454700D03*
X226999Y778667D03*
X490803Y501502D03*
X490818Y494161D03*
X490823Y497927D03*
X519516Y424009D03*
X521052Y552477D03*
X521213Y548807D03*
X696939Y759399D03*
X696992Y762972D03*
X698027Y817304D03*
X697975Y820842D03*
G54D12*
X-138100Y222300D03*
Y241300D03*
Y260300D03*
Y279300D03*
Y298300D03*
Y317300D03*
Y336300D03*
X-70100Y222300D03*
X-87100D03*
X-104100D03*
X-121100D03*
X-70100Y241300D03*
X-87100D03*
X-104100D03*
X-121100D03*
X-70100Y260300D03*
X-87100D03*
X-104100D03*
X-121100D03*
X-70100Y279300D03*
X-87100D03*
X-104100D03*
X-121100D03*
X-70100Y298300D03*
X-87100D03*
X-104100D03*
X-121100D03*
X-70100Y317300D03*
X-87100D03*
X-104100D03*
X-121100D03*
X-70100Y336300D03*
X-87100D03*
X-104100D03*
X-121100D03*
X-2100Y222300D03*
X-19100D03*
X-36100D03*
X-53100D03*
X-2100Y241300D03*
X-19100D03*
X-36100D03*
X-53100D03*
X-2100Y260300D03*
X-19100D03*
X-36300Y260000D03*
X-53100Y260300D03*
X9243Y334400D03*
X-1900Y288300D03*
X-49400Y284500D03*
X-19600Y279500D03*
X-36100Y279300D03*
X-2100Y298300D03*
X-19100D03*
X-36100D03*
X-53100D03*
X-2100Y317300D03*
X-19100D03*
X-36100D03*
X-53100D03*
X-2100Y336300D03*
X-19100D03*
X-36100D03*
X-53100D03*
X-1600Y413600D03*
Y394600D03*
Y375600D03*
Y356600D03*
X-52600Y413600D03*
X-35600D03*
X-18600D03*
X-52600Y394600D03*
X-35600D03*
X-18600D03*
X-52600Y375600D03*
X-35600D03*
X-18600D03*
X-52600Y356600D03*
X-35600D03*
X-18600D03*
X-19400Y483400D03*
X-2400D03*
X-36400D03*
X-53400D03*
X-1500Y470300D03*
Y451300D03*
Y432300D03*
X-52500Y470300D03*
X-35500D03*
X-18500D03*
X-52500Y451300D03*
X-35500D03*
X-18500D03*
X-52500Y432300D03*
X-35500D03*
X-18500D03*
X8788Y453864D03*
X-19400Y502400D03*
X-2400D03*
X-36400D03*
X-53400D03*
X63400Y89300D03*
X51900Y83600D03*
X43980Y86200D03*
X68000Y87750D03*
X42700Y110500D03*
X67300Y107200D03*
X63100Y107300D03*
X48100Y133900D03*
X59200Y95573D03*
X51800Y93500D03*
X79600Y91500D03*
X51900Y89900D03*
X79500Y85700D03*
X77200Y95500D03*
X69800Y176800D03*
X31500Y185700D03*
X76250Y148850D03*
X70200Y199300D03*
X47900Y145500D03*
X48100Y153800D03*
X43800Y204800D03*
X38800Y194300D03*
X38700Y199700D03*
X73700D03*
X49500Y169300D03*
X61751Y181464D03*
X44100Y200600D03*
X49286Y203671D03*
X69000Y202700D03*
X77200Y189000D03*
X60200Y193550D03*
X29600Y200100D03*
X26100Y187300D03*
X39800Y172900D03*
X27800Y191100D03*
X74700Y191700D03*
X70675Y145000D03*
X60009Y255077D03*
X55624Y255132D03*
X59523Y271123D03*
X60102Y263180D03*
X55883Y263570D03*
X33400Y266400D03*
X59258Y246890D03*
X60069Y237965D03*
X64700Y215100D03*
X51600Y217000D03*
X50500Y243100D03*
X70636Y272953D03*
X79189Y235119D03*
X43900Y209000D03*
X72001Y265901D03*
X69400Y207400D03*
X76019Y222534D03*
X42507Y296616D03*
X59316Y300366D03*
X59096Y289139D03*
X59523Y281330D03*
X52257Y276649D03*
X55420Y288656D03*
X17100Y311700D03*
X43181Y278603D03*
X39563Y307968D03*
X21876Y282289D03*
X41418Y287473D03*
X61776Y367194D03*
X43345Y386857D03*
X43639Y374043D03*
X29700Y355000D03*
X27284Y358500D03*
X67527Y381818D03*
X43569Y379314D03*
X65605Y367307D03*
X51422Y473540D03*
X24315Y472668D03*
X47307Y465104D03*
X29064Y471345D03*
X55295Y479672D03*
X20715Y485712D03*
X20276Y477090D03*
X20928Y453864D03*
X21300Y468000D03*
X38800Y535700D03*
X38200Y528900D03*
X51383Y514037D03*
X63862Y512438D03*
X73542Y514340D03*
X37200Y513500D03*
X32026Y516764D03*
X60800Y505200D03*
X56121Y494271D03*
X21090Y497108D03*
X54659Y513125D03*
X67140Y511501D03*
X50893Y534434D03*
X66300Y548000D03*
X67244Y535455D03*
X72677Y528615D03*
X69220Y614992D03*
X59379Y644787D03*
X57500Y662600D03*
X47000Y645300D03*
X69911Y676938D03*
X73900Y664900D03*
X77000Y646200D03*
X72930Y645818D03*
X67257Y643668D03*
X60122Y747800D03*
X64000Y765600D03*
X47100Y746000D03*
X69217Y732676D03*
X73325Y760926D03*
X67809Y758190D03*
X65447Y711413D03*
X62066Y711051D03*
X65356Y707010D03*
X61193Y706973D03*
X73282Y778907D03*
X106300Y105900D03*
X81150Y120850D03*
X89400Y120800D03*
X85250Y120850D03*
X117500Y106200D03*
X85000Y107800D03*
X111700Y106100D03*
X89000Y107700D03*
X82400Y89500D03*
X132500Y124600D03*
X83800Y188800D03*
X111482Y202800D03*
X113815Y194333D03*
X122400Y199000D03*
X80685Y192398D03*
X84641Y204036D03*
X79900Y148700D03*
X103300Y160900D03*
X112000Y160700D03*
X119900Y162200D03*
X125300Y162300D03*
X122100Y203300D03*
X96900Y189286D03*
X107771Y182699D03*
X145400Y161955D03*
X114700Y157000D03*
X107672Y156597D03*
X98700Y156200D03*
X122200Y156700D03*
X80207Y139965D03*
X81200Y176000D03*
X93303Y154970D03*
X144950Y177338D03*
X85713Y151540D03*
X84900Y145300D03*
X125700Y225200D03*
X121000Y225300D03*
X109400Y225400D03*
X90813D03*
X79800Y225900D03*
X87227Y242891D03*
X87263Y264658D03*
X90652Y265960D03*
X87698Y246708D03*
X94051Y265872D03*
X91230Y247047D03*
X91819Y250396D03*
X94793Y252595D03*
X98211Y252758D03*
X142933Y251431D03*
X132651Y255357D03*
X138228Y260175D03*
X124933Y270414D03*
X136427Y251413D03*
X124874Y273953D03*
X137809Y247647D03*
X135592Y257933D03*
X116566Y254205D03*
X114229Y270684D03*
X119242Y252107D03*
X112042Y275903D03*
X121685Y249741D03*
X121741Y246341D03*
X118219Y274497D03*
X122572Y258147D03*
X121599Y274869D03*
X130567Y258051D03*
X113558Y261260D03*
X111008Y242830D03*
X106381Y259865D03*
X106504Y243329D03*
X103610Y268626D03*
X102713Y242975D03*
X103003Y260260D03*
X108652Y247260D03*
X107887Y266647D03*
X101242Y265901D03*
X100415Y246679D03*
X126611Y258265D03*
X84863Y229783D03*
X134529Y264470D03*
X137190Y266587D03*
X131901Y267444D03*
X132163Y271041D03*
X137690Y273752D03*
X110610Y206436D03*
X125600Y221200D03*
X113863Y228669D03*
X102559Y228575D03*
X97885Y228339D03*
X147013Y225483D03*
X122000Y207300D03*
X94600Y206900D03*
X94548Y211258D03*
X109534Y314564D03*
X92682Y331571D03*
X140103Y328216D03*
X117460Y335158D03*
X128964Y339470D03*
X148102Y338366D03*
X119603Y285731D03*
X124478Y280855D03*
X95202Y290958D03*
X98565Y290455D03*
X102107Y290439D03*
X105603Y291092D03*
X95146Y279609D03*
X110808Y291075D03*
X98546Y279609D03*
X114915Y290203D03*
X104413Y278608D03*
X117027Y278475D03*
X148834Y284832D03*
X107750Y277953D03*
X135308Y276806D03*
X139784Y276432D03*
X142241Y278783D03*
X121477Y314973D03*
X135613Y308903D03*
X95400Y383083D03*
X84200Y380000D03*
X118744Y525279D03*
X140399Y525238D03*
X129199Y525271D03*
X107103Y525057D03*
X95599Y525026D03*
X84799Y524898D03*
X90878Y585185D03*
X85654Y659044D03*
X83960Y632636D03*
X90681Y690157D03*
X90174Y678675D03*
X85600Y647837D03*
X83500Y653600D03*
Y640044D03*
X84900Y747900D03*
X93840Y699686D03*
X90814Y734451D03*
X91027Y724985D03*
X91094Y715818D03*
X84703Y758885D03*
X84182Y764879D03*
X90746Y712435D03*
X90947Y709040D03*
X91003Y705214D03*
X91130Y701741D03*
X85300Y755100D03*
X85000Y775900D03*
X84100Y769000D03*
X220131Y58163D03*
X197900Y82000D03*
X201237Y106350D03*
X210356Y99104D03*
X210680Y84396D03*
X201614Y89932D03*
X212028Y93512D03*
X212800Y125800D03*
X182400Y128300D03*
X175598Y128436D03*
X220100Y123600D03*
X166700Y128800D03*
X172200Y128300D03*
X179000D03*
X205628Y89404D03*
X152350Y131084D03*
X204849Y106438D03*
X200100Y101200D03*
X170302Y147100D03*
X158100Y166800D03*
X160311Y141680D03*
X219548Y174651D03*
X189600Y166700D03*
X189700Y170200D03*
X190018Y173586D03*
X188961Y162715D03*
X211700Y181600D03*
X208200Y153500D03*
X203900D03*
X200100Y146500D03*
Y150400D03*
X199100Y153800D03*
X194800D03*
X174339Y151172D03*
X178400Y152300D03*
X167015Y167633D03*
X163550Y179657D03*
X172645Y179104D03*
X177087Y178920D03*
X183120Y266103D03*
X183082Y271969D03*
X182853Y256107D03*
X183956Y261452D03*
X168010Y267909D03*
X219717Y211198D03*
X182177Y251208D03*
X154300Y227900D03*
X171200Y233000D03*
X185563Y245456D03*
X175064Y232857D03*
X185740Y240983D03*
X185502Y237383D03*
X152663Y272053D03*
X192284Y258847D03*
X150666Y243134D03*
X195698Y259749D03*
X196365Y256414D03*
X168324Y246397D03*
X171762Y258345D03*
X167894Y243024D03*
X167760Y239626D03*
X156800Y230500D03*
X152663Y267791D03*
X216335Y218212D03*
X196344Y237383D03*
X196078Y248183D03*
X196021Y244556D03*
X196151Y240983D03*
X151519Y250193D03*
X180641Y231683D03*
X186319Y268076D03*
X183043Y276658D03*
X183707Y289861D03*
X183653Y283162D03*
X184188Y340638D03*
X162135Y332650D03*
X185042Y286734D03*
X167051Y293752D03*
X188273Y285674D03*
X187118Y281963D03*
X163142Y294193D03*
X183466Y294017D03*
X152580Y285530D03*
X172818Y288683D03*
X216178Y411331D03*
X219144Y414536D03*
X195307Y355649D03*
X206775Y348954D03*
X173508Y348462D03*
X177715Y397471D03*
X212500Y395500D03*
X217800Y395900D03*
X200161Y416474D03*
X206142Y413945D03*
X206871Y397177D03*
X210042Y412265D03*
X175767Y380311D03*
X189073Y380379D03*
X185276Y380362D03*
X181242Y380481D03*
X197565Y380257D03*
X203379Y380312D03*
X169600Y380500D03*
X173864Y397677D03*
X213400Y434601D03*
X181980Y458681D03*
X210772Y431456D03*
X200453Y439066D03*
X203186Y451492D03*
X180445Y422567D03*
X176991Y463723D03*
X184750Y427953D03*
X208947Y443700D03*
X196803Y444462D03*
X201400Y434400D03*
X202764Y444274D03*
X190887Y424438D03*
X174500Y424100D03*
X182060Y443776D03*
X211243Y462005D03*
X203406Y454885D03*
X195038Y477148D03*
X180313Y446694D03*
X176915Y446556D03*
X195400Y452051D03*
X208632Y457048D03*
X181034Y427967D03*
X177700Y427300D03*
X184399Y525203D03*
X195499D03*
X206699D03*
X217899Y525103D03*
X162615Y525220D03*
X173537D03*
X151684Y525258D03*
X210223Y501477D03*
X213500Y503600D03*
X216300Y499600D03*
X193016Y496643D03*
X219492Y517832D03*
X219590Y740816D03*
X181642Y837321D03*
Y827853D03*
X181772Y818429D03*
X159926Y813000D03*
X201663Y827680D03*
X201142Y837191D03*
X181081Y856307D03*
X181124Y847013D03*
X200798Y846849D03*
X266700Y46900D03*
X263000Y47000D03*
X257500Y46900D03*
X253800Y47000D03*
X244900Y47300D03*
X248600Y47200D03*
X235000Y47500D03*
X238700Y47400D03*
X225231Y58420D03*
X254498Y88487D03*
X251687Y98033D03*
X261830Y81230D03*
X241101D03*
X256928Y69301D03*
X241132Y85023D03*
X259815Y94233D03*
X248000Y114500D03*
X242488Y88466D03*
X223948Y174292D03*
X246100Y151300D03*
Y155800D03*
Y160400D03*
X231049Y188760D03*
X251700Y135484D03*
X231350Y222067D03*
X238614Y217763D03*
X222496Y222320D03*
X223129Y210901D03*
X224664Y293860D03*
X257400Y403206D03*
X239600Y405600D03*
X237800Y411200D03*
X226576Y401835D03*
X228243Y380358D03*
X231915Y380533D03*
X244928Y367685D03*
X238151Y356092D03*
X228510Y367624D03*
X240715Y380333D03*
X222269Y402278D03*
X228949Y410741D03*
X225421Y410908D03*
X269840Y386256D03*
X239693Y396029D03*
X257500Y399300D03*
X264600Y380500D03*
X270800Y408500D03*
X261300Y402355D03*
X275500Y415400D03*
X264124Y408219D03*
X258267Y408800D03*
X233400Y409700D03*
X255010Y367624D03*
X273554Y386722D03*
X223600Y456200D03*
X246502Y472752D03*
X255622Y461532D03*
X263000Y438800D03*
X260600Y435900D03*
X258299Y432800D03*
X250400Y440000D03*
X249600Y428100D03*
X237700Y458000D03*
X269300Y486200D03*
X249600Y432500D03*
X239000Y440300D03*
X244800Y454500D03*
X229600Y460700D03*
X289200Y445100D03*
X252200Y486700D03*
X290300Y462400D03*
X290011Y456234D03*
X289000Y449200D03*
X221035Y453935D03*
X279120Y440440D03*
X276761Y443421D03*
X277575Y449398D03*
X270714Y458323D03*
X263719Y455536D03*
X259779Y456823D03*
X220768Y418393D03*
X260322Y462288D03*
X256852Y465331D03*
X258221Y469246D03*
X235069Y464940D03*
X257184Y421241D03*
X271342Y440630D03*
X235600Y433300D03*
X264775Y459236D03*
X279789Y432846D03*
X285565Y438912D03*
X250400Y473300D03*
X260481Y473769D03*
X253214Y469048D03*
X228400Y486400D03*
X228001Y474064D03*
X226000Y458700D03*
X249845Y469508D03*
X229300Y442500D03*
X225700Y496800D03*
X226115Y507011D03*
X229513Y507141D03*
X232912Y507242D03*
X224515Y532633D03*
X237336Y531828D03*
X236700Y539300D03*
X240400Y534500D03*
X245800D03*
X241300Y539300D03*
X236300Y535600D03*
X243200Y531700D03*
X288586Y493703D03*
X268215Y490733D03*
X251755Y491731D03*
X270700Y495400D03*
X274315Y497133D03*
X283657Y532832D03*
X280259Y532714D03*
X232200Y492100D03*
X231739Y495469D03*
X248286Y489208D03*
X242100Y489000D03*
X268600Y529800D03*
X256300Y531400D03*
X289400Y511700D03*
X243300Y527900D03*
X247256Y529218D03*
X251700Y531500D03*
X268500Y525800D03*
X238118Y492166D03*
X246132Y492160D03*
X289405Y515437D03*
X228500Y498900D03*
X281183Y592936D03*
X223671Y740896D03*
X228249Y761450D03*
X223129Y764830D03*
X271970Y798668D03*
X282413Y798410D03*
X228021Y787335D03*
X223596Y782163D03*
X236973Y795418D03*
X237950Y774979D03*
X237815Y779065D03*
X226949Y782735D03*
X235169Y791455D03*
X240130Y789012D03*
X277254Y852624D03*
X314000Y405200D03*
X316800Y415900D03*
X299800Y398500D03*
X332600Y400100D03*
X305456Y481787D03*
X335532Y485626D03*
X323215Y485633D03*
X304783Y467192D03*
X295115Y476433D03*
Y473033D03*
X297715Y479588D03*
X306603Y459523D03*
X301437Y426833D03*
X304200Y432600D03*
X300603Y432406D03*
X309200Y444700D03*
X331800Y440400D03*
X331900Y444600D03*
X356700Y437500D03*
X348800D03*
X341500Y437400D03*
X291300Y468600D03*
X308900Y449100D03*
X327900Y438100D03*
X341430Y459351D03*
X345735Y460843D03*
X349800Y460000D03*
X353698Y460323D03*
X357812Y460406D03*
X297238Y429641D03*
X304550Y424222D03*
X300059Y422844D03*
X318015Y493833D03*
X334315Y496733D03*
X330815Y493433D03*
X327115Y489533D03*
X344815Y494933D03*
X321415Y497133D03*
X304000Y538500D03*
X308800Y540925D03*
X350400Y512000D03*
X335600Y511400D03*
X304700Y509500D03*
X317900Y520100D03*
X314628Y517729D03*
X343905Y519116D03*
X324400Y570500D03*
X346510Y796385D03*
X350765D03*
X315696Y798445D03*
X294148Y798547D03*
X305437Y798205D03*
X362793Y77815D03*
Y126096D03*
X381025Y73748D03*
Y120650D03*
X373496Y140021D03*
X365131Y135484D03*
X413900Y396400D03*
X428343Y463067D03*
X420575Y467336D03*
X382695Y467033D03*
Y471133D03*
X388884Y468631D03*
X387143Y462647D03*
X378700Y437600D03*
X371200Y437800D03*
X363800Y437700D03*
X428616Y429466D03*
X391500Y459000D03*
X399900Y458600D03*
X421273Y439381D03*
X361533Y460222D03*
X365241Y460010D03*
X416588Y467839D03*
X361814Y796557D03*
X500295Y401715D03*
X501800Y387600D03*
X473838Y385675D03*
X474106Y382285D03*
X500526Y394177D03*
X473605Y389068D03*
X499764Y411324D03*
X497279Y382551D03*
X435138Y460661D03*
X457091Y486699D03*
X475600Y462100D03*
X452300Y420900D03*
X458900Y446600D03*
X483100Y449900D03*
X488500Y474200D03*
X450300Y459900D03*
X471300Y482200D03*
X449000Y480000D03*
X438316Y449493D03*
X438294Y453811D03*
X501700Y477200D03*
X483530Y541762D03*
X487073Y554094D03*
X482183Y535169D03*
X483008Y500529D03*
X469932Y518034D03*
X447307Y511890D03*
X447090Y497242D03*
X471410Y490049D03*
X498994Y488322D03*
X501802Y490240D03*
X494400Y493600D03*
Y497500D03*
X471650Y493916D03*
X494410Y501344D03*
X458713Y518034D03*
X482200Y529100D03*
X484200Y538000D03*
X483800Y545700D03*
X452652Y495705D03*
X465900Y501200D03*
X523200Y399400D03*
X506100Y380000D03*
X517041Y388700D03*
X513500Y399060D03*
X520900Y388100D03*
X536928Y411324D03*
X514000Y486293D03*
X508306Y428179D03*
X523462Y423957D03*
X503923Y423910D03*
X536736Y418540D03*
X504500Y479500D03*
X514073Y552477D03*
X503300Y539700D03*
X529000Y550500D03*
X502318Y535328D03*
X521002Y555911D03*
X525300Y552800D03*
X516900Y561200D03*
X528000Y562900D03*
X512700Y560000D03*
X637200Y393900D03*
X629100Y536000D03*
X632600Y555200D03*
X636200Y555100D03*
X640100Y550600D03*
X638300Y511800D03*
X641800Y519000D03*
X639500Y521900D03*
X641700Y510300D03*
X662100Y394600D03*
X667979Y486293D03*
X702400Y431500D03*
X698300Y431600D03*
X693509Y431701D03*
X689111Y431612D03*
X684869Y431611D03*
X680738Y431633D03*
X711409Y467621D03*
X707700Y476500D03*
X707890Y467821D03*
X684259Y476130D03*
X682774Y449737D03*
X667745Y456089D03*
X662604Y463284D03*
X671915Y543133D03*
X694700Y547700D03*
X688800Y540450D03*
X702400Y554800D03*
X705927Y538650D03*
X663600Y535395D03*
X644600Y556700D03*
X652400Y545200D03*
X674375Y509826D03*
X700512Y510204D03*
X643833Y549325D03*
X702000Y546581D03*
X702400Y550600D03*
X684600Y542100D03*
X665499Y556600D03*
X651800Y540295D03*
X711400Y515400D03*
X711900Y521500D03*
X675400Y538100D03*
X662200Y547300D03*
X709600Y524100D03*
X658314Y526697D03*
X672168Y538889D03*
X676115Y542633D03*
X712102Y542133D03*
X707589Y515400D03*
X700900Y539500D03*
X669200Y559600D03*
X656817Y567131D03*
X697600Y560000D03*
X701400Y560200D03*
X707391Y564566D03*
X643100Y589900D03*
X689945Y758289D03*
X700989Y759255D03*
X667982Y739870D03*
X681402Y757754D03*
X663575Y742289D03*
X668987Y731465D03*
X691075Y820814D03*
X711116Y796516D03*
X702290Y820921D03*
X680480Y773302D03*
X678755Y784815D03*
X676727Y790555D03*
X679630Y795856D03*
X680239Y802378D03*
X682693Y806283D03*
X684732Y810518D03*
X669886Y786112D03*
X666516Y784722D03*
X686308Y834802D03*
X646342Y826469D03*
X685799Y770894D03*
X690211Y827401D03*
X683715Y852233D03*
X710727Y862002D03*
X678351Y854383D03*
X679332Y841866D03*
X681156Y844982D03*
X681542Y848361D03*
X722687Y120650D03*
X727300Y273200D03*
X758200Y338900D03*
X756700Y370600D03*
X762900Y387400D03*
X768000Y457700D03*
X767700Y473300D03*
X729700Y551500D03*
X729600Y540400D03*
X724000Y532600D03*
X722682Y538700D03*
X716300Y517125D03*
X719800Y525000D03*
X719866Y528656D03*
X751965Y522097D03*
X747886D03*
X757848Y513543D03*
X752874Y534854D03*
X737297Y517903D03*
X756523Y520272D03*
X749493Y535216D03*
X725100Y519600D03*
X746000Y549700D03*
X726800Y527400D03*
X723538Y526440D03*
X742607Y549481D03*
X752100Y506500D03*
X749500Y508800D03*
X742000Y505000D03*
X762275Y512870D03*
X744073Y522097D03*
X755862Y516303D03*
X756400Y508100D03*
X756272Y534995D03*
X763000Y490800D03*
X717879Y564572D03*
X725900Y561800D03*
X737400Y576200D03*
X766358Y564600D03*
X727700Y584400D03*
X758400Y568500D03*
X742600Y577100D03*
X756100Y658700D03*
X757600Y639700D03*
X746669Y740179D03*
X743653Y744114D03*
X741453Y748054D03*
X738850Y751989D03*
X734450Y755929D03*
X730967Y759864D03*
X724305Y770450D03*
X723678Y774016D03*
X727477Y775212D03*
X724733Y779559D03*
X730028Y782297D03*
X724859Y784497D03*
X742663Y788885D03*
X729988Y787114D03*
X739510Y795264D03*
X725239Y788970D03*
X745230Y793211D03*
X729486Y791416D03*
X742370Y799077D03*
X725407Y794540D03*
X747659Y796960D03*
X744790Y802781D03*
X749593Y803991D03*
X747556Y808994D03*
X749629Y812608D03*
X722443Y826463D03*
X721704Y829981D03*
X724858Y831254D03*
X723801Y834857D03*
X726332Y837128D03*
X733066Y836450D03*
X729250Y850000D03*
X721243Y850725D03*
X718263Y863827D03*
X745100Y859405D03*
X721112Y854419D03*
X724093Y840187D03*
X726776Y842277D03*
X733796Y854172D03*
G54D22*
X45100Y93600D03*
X63463Y267083D03*
X55863D03*
X62963Y272683D03*
X63463Y258783D03*
X55863Y258883D03*
X63463Y254683D03*
X55863Y251483D03*
X63663Y250483D03*
Y246283D03*
X55746Y242114D03*
X63563Y242083D03*
X63663Y237683D03*
X63463Y262883D03*
X63401Y294778D03*
Y290678D03*
X55463Y285083D03*
X63096Y285730D03*
Y281630D03*
X55463Y276783D03*
X62963D03*
X47280Y373862D03*
X62822Y517540D03*
X51779Y521570D03*
X40455Y517250D03*
X73842Y521666D03*
X87841Y203800D03*
X115171Y206661D03*
X140153Y331742D03*
X129017Y335856D03*
X117555Y331729D03*
X129463Y517903D03*
X84962Y517603D03*
X95985Y521826D03*
X107207Y517857D03*
X118351Y522079D03*
X140512Y522038D03*
X217959Y106010D03*
X203025Y98053D03*
X151152Y335814D03*
X173238Y344153D03*
X162185Y339913D03*
X206480Y356594D03*
X217685Y363914D03*
X195438Y352449D03*
X184357Y348289D03*
X189566Y481243D03*
X173649Y517848D03*
X151474Y517879D03*
X162505Y522020D03*
X206863Y522003D03*
X195663Y517803D03*
X184663Y522003D03*
X246715Y93933D03*
X246690Y89833D03*
X244646Y77735D03*
X244790Y102533D03*
X244652Y73668D03*
X223702Y214585D03*
X249153Y387029D03*
X242697Y432409D03*
X235300Y482954D03*
X231162Y779010D03*
X231266Y783159D03*
X231221Y787335D03*
X282342Y794780D03*
X334746Y793055D03*
X350527Y792923D03*
X305499Y794862D03*
X315715Y795010D03*
X294176Y794808D03*
X487430Y532955D03*
X487438Y541335D03*
X487123Y549911D03*
X475287Y490049D03*
X457141Y490002D03*
X487499Y508498D03*
X487502Y512828D03*
X447418Y508324D03*
X504700Y389700D03*
X508334Y424179D03*
X525410Y531644D03*
X525388Y527470D03*
X708009Y453923D03*
X657609Y474323D03*
X712109Y458023D03*
X661709Y470223D03*
X674109Y457923D03*
X678509Y453723D03*
X689000Y537000D03*
X728709Y474523D03*
X724509Y470223D03*
X725791Y857331D03*
G54D31*
X77688Y184954D03*
X24894Y493063D03*
X149631Y176850D03*
X157313Y171759D03*
X208182Y427789D03*
X211343Y418666D03*
X244700Y461100D03*
X235756Y478217D03*
X236673Y468923D03*
X299174Y475788D03*
X294700Y462500D03*
X299213Y471007D03*
G54D40*
X77453Y529424D03*
X69970Y525139D03*
X66497Y525155D03*
X59007Y529328D03*
X55470Y529248D03*
X47790Y524900D03*
X44031Y524996D03*
X136663Y525503D03*
X133163Y525603D03*
X147678Y529668D03*
X144206Y529634D03*
X125501Y529646D03*
X122044Y529662D03*
X114546Y525552D03*
X110786Y525551D03*
X103330Y529565D03*
X99797Y529446D03*
X92158Y525234D03*
X88606Y525233D03*
X81117Y529360D03*
X204811Y81527D03*
X153061Y172312D03*
X219655Y218098D03*
X200498Y392164D03*
X205667Y410283D03*
X214163Y529603D03*
X210563Y529703D03*
X202963Y525503D03*
X199363D03*
X191863Y529803D03*
X188363D03*
X180845Y525511D03*
X177324Y525527D03*
X169812Y529747D03*
X166180Y529746D03*
X158691Y525493D03*
X155181Y525542D03*
X258530Y85526D03*
X243200Y524300D03*
X277254Y849165D03*
X337612Y434023D03*
X341344D03*
X360415D03*
X356714D03*
X352814D03*
X348914D03*
X345014D03*
X387100D03*
X383102D03*
X371187D03*
X367432D03*
X363968D03*
X379184D03*
X375464D03*
G54D13*
X4800Y48600D03*
X5800Y6400D03*
X5000Y71900D03*
Y91900D03*
X5100Y111800D03*
X4900Y130400D03*
X5000Y150500D03*
X5300Y170000D03*
X9151Y473051D03*
X8672Y487593D03*
X7075Y527972D03*
X7927Y509647D03*
X8140Y637282D03*
X8246Y771416D03*
X45700Y61000D03*
X65500Y60800D03*
X75500D03*
X45900Y50000D03*
X65700Y49800D03*
X50800Y39500D03*
X70700Y45800D03*
X55800Y61300D03*
X59900Y40600D03*
X53200Y26300D03*
X50600Y6000D03*
X50500Y67700D03*
X70500Y72000D03*
X60800Y72500D03*
X71800Y100400D03*
X58800Y101600D03*
X57200Y175300D03*
X68200Y218900D03*
X21515Y378719D03*
X34015Y379038D03*
X40915Y389933D03*
X27515Y413492D03*
X50900Y369500D03*
X55500Y383100D03*
X40715Y382433D03*
X57900Y372700D03*
X40381Y472477D03*
X43015Y453102D03*
X23662Y429056D03*
X10515Y436844D03*
X52215Y422661D03*
X11803Y444233D03*
X21015Y440028D03*
X27293Y435619D03*
X45815Y461517D03*
X25415Y449205D03*
X51515Y479433D03*
X16158Y477255D03*
X17228Y453864D03*
X47315Y469617D03*
X39600Y494800D03*
X38200Y490900D03*
X35100Y494400D03*
X33600Y512600D03*
X37329Y524472D03*
X33880Y526500D03*
X33921Y520414D03*
X18809Y491871D03*
X17212Y532250D03*
X18064Y513925D03*
X18277Y641560D03*
X9844Y658803D03*
X19981Y663081D03*
X9631Y753837D03*
X19768Y758115D03*
X18383Y775694D03*
X55459Y780063D03*
X48300Y775300D03*
X87900Y47800D03*
X90900Y42400D03*
X80400Y47800D03*
X124100Y6700D03*
X110800Y48800D03*
X120200Y48400D03*
X98700Y48900D03*
X143900Y38000D03*
X108100Y35300D03*
X146900Y48500D03*
X109700Y6400D03*
X119700Y35400D03*
X139800Y31100D03*
X96300Y6100D03*
X147200Y7300D03*
X108600Y19900D03*
X126500Y20100D03*
X147500Y90200D03*
X142167Y106366D03*
X142101Y98650D03*
X111100Y75500D03*
X100000Y75600D03*
X121700Y75300D03*
X85300Y70200D03*
X110000Y90700D03*
X130415Y168033D03*
X126300Y180209D03*
X126700Y173500D03*
X136291Y179968D03*
X136100Y173800D03*
X148715Y158433D03*
X84600Y199700D03*
X87100Y209300D03*
X95100Y215200D03*
X109100Y214300D03*
X134200Y217300D03*
X130000Y217200D03*
X134600Y222200D03*
X130000Y228000D03*
X128918Y307533D03*
X106051Y767209D03*
X122899Y825236D03*
X112762Y820958D03*
X116188Y771487D03*
X131900Y893200D03*
X120874Y857517D03*
X110737Y853239D03*
X131700Y915700D03*
X89871Y917500D03*
X209100Y51700D03*
X191700Y63300D03*
X209200Y65100D03*
X200700Y51700D03*
X185100Y55900D03*
X208900Y58600D03*
X192000Y55900D03*
X200700Y58300D03*
X184700Y63100D03*
X173200Y10900D03*
X213700Y35200D03*
X186000D03*
X197796Y12653D03*
X160600Y49100D03*
X153200Y48700D03*
X167500Y49000D03*
X160500Y19700D03*
X170400Y31100D03*
X150600Y37800D03*
X154500Y90000D03*
X158000Y79600D03*
X165200Y79500D03*
X163300Y95900D03*
X163500Y105500D03*
X151800Y72400D03*
X209000Y72300D03*
X201500D03*
X177100Y99500D03*
X177200Y104800D03*
X177300Y94200D03*
Y88500D03*
X184700D03*
X190700Y77800D03*
X201200Y65600D03*
X191000Y71300D03*
X184500Y71200D03*
X177400Y71400D03*
X177500Y77900D03*
X183700Y78100D03*
X191500Y88500D03*
X204200Y126700D03*
X206600Y130300D03*
X201900D03*
X209800Y88600D03*
X217909Y110100D03*
X183900Y150600D03*
X215700Y181620D03*
X154800Y145800D03*
X181200Y176300D03*
X180015Y202933D03*
X207495Y192761D03*
X169800Y155796D03*
X165162Y155909D03*
X169709Y160049D03*
X165388Y160094D03*
X163979Y141189D03*
X202300Y181000D03*
X170315Y291733D03*
X200315Y400633D03*
X189700Y403800D03*
X210600Y423000D03*
X181300Y463300D03*
X204700Y441000D03*
X181300Y417800D03*
X215100Y453900D03*
X207200Y447100D03*
X186515Y498933D03*
X202715Y501618D03*
X196400Y585300D03*
X179000Y624800D03*
X217015Y737933D03*
X193600Y702400D03*
X179100Y714600D03*
X202300Y742000D03*
X213415Y748233D03*
X189273Y902478D03*
X213138Y905780D03*
X218729Y857629D03*
X200460Y913771D03*
X283615Y59733D03*
X282282Y47189D03*
X286930D03*
X285615Y52233D03*
X285015Y42433D03*
X233900Y32500D03*
X252187Y23895D03*
X286651Y14571D03*
X224431Y15210D03*
X248900Y8400D03*
X232615Y106010D03*
X282444Y106834D03*
X225919Y88394D03*
X225937Y80731D03*
X221710Y80767D03*
X221722Y88431D03*
X230158Y88359D03*
X230123Y80805D03*
X225851Y73774D03*
X221740Y73844D03*
X229870Y73970D03*
X228169Y68374D03*
X224169Y68520D03*
X228728Y96613D03*
X224285Y96750D03*
X229400Y134000D03*
X242800Y93300D03*
X238771Y101724D03*
X235700Y204940D03*
X227900Y180500D03*
X258741Y193852D03*
X227116Y223400D03*
X290215Y269533D03*
X256823Y221979D03*
X246169Y246270D03*
X230774Y270268D03*
X241694Y274956D03*
X228635Y385956D03*
X232788Y385893D03*
X253700Y393900D03*
X245100Y386300D03*
X248900Y407500D03*
X224403Y405302D03*
X245000Y380700D03*
X257800Y428100D03*
X222900Y463100D03*
X224800Y471600D03*
X248410Y466092D03*
X233700Y487100D03*
X242900Y483600D03*
X228000Y478400D03*
X242900Y473600D03*
X238000Y422100D03*
X227400D03*
X232750Y422200D03*
X243900Y424500D03*
X250800Y436300D03*
X227915Y503233D03*
X228415Y539233D03*
X229764Y513034D03*
X234416Y512963D03*
X238924Y512390D03*
X243100Y516300D03*
X245963Y511890D03*
X250975Y511729D03*
X255500Y514000D03*
X264000Y513400D03*
X225215Y512533D03*
X277300Y572500D03*
X259600Y568400D03*
X271949Y648699D03*
X272588Y681087D03*
X244248Y682153D03*
X255542Y665532D03*
X241904Y652321D03*
X289634Y659352D03*
X229715Y747933D03*
X226015Y737933D03*
X284520Y743307D03*
X282176Y713475D03*
X230515Y793233D03*
X240615Y782733D03*
X240715Y771333D03*
X230823Y823850D03*
X253623Y867319D03*
X254262Y899707D03*
X225922Y900773D03*
X237216Y884152D03*
X223578Y870941D03*
X285585Y897363D03*
X283241Y867531D03*
X264212Y903112D03*
X299300Y41300D03*
X321300Y43200D03*
X351800Y42200D03*
X360500Y42600D03*
X330000Y42800D03*
X329900Y37100D03*
X321300D03*
X360500Y36700D03*
X291373Y47394D03*
X299300Y46400D03*
X351800Y36300D03*
X299600Y62100D03*
X351900Y62000D03*
X360200Y62300D03*
X329500Y62600D03*
X321300Y63100D03*
X325006Y15636D03*
X299500Y68200D03*
X352000Y68000D03*
X360200Y68200D03*
X329600D03*
X321400Y68500D03*
X344663Y108965D03*
X312275Y98098D03*
X327515Y185333D03*
X354197Y158187D03*
X301140Y161383D03*
X297915Y135484D03*
X352066Y262596D03*
X307320Y223390D03*
X301781Y258122D03*
X322022Y279856D03*
X291500Y473900D03*
X320207Y428442D03*
X320166Y432442D03*
X309648Y582024D03*
X319679Y655730D03*
X320318Y688118D03*
X291978Y689184D03*
X303272Y672563D03*
X347378Y688332D03*
X358672Y671711D03*
X345034Y658500D03*
X302115Y693462D03*
X360803Y704312D03*
X333102Y737766D03*
X344396Y721145D03*
X330758Y707934D03*
X312221Y709853D03*
X312860Y742241D03*
X295814Y726686D03*
X319171Y767846D03*
X313959Y724732D03*
X354623Y896937D03*
X352279Y867105D03*
X313286Y863909D03*
X313925Y896297D03*
X296879Y880742D03*
X332436Y858576D03*
X337648Y901690D03*
X382100Y61900D03*
X401343Y58465D03*
X394098Y20059D03*
X362775D03*
X412506Y33484D03*
X382200Y68500D03*
X410025Y87658D03*
X378715Y162033D03*
X390208Y180135D03*
X366982Y198886D03*
X407769Y204757D03*
X384668Y247681D03*
X376144Y279856D03*
X380956Y408290D03*
X376513Y408085D03*
X371865D03*
X380392Y416962D03*
X375949Y416757D03*
X371301D03*
X366653Y416484D03*
X367217Y407812D03*
X430515Y395333D03*
X366719Y424200D03*
X371367Y424473D03*
X376015D03*
X380458Y424678D03*
X394815Y420433D03*
X372815Y474033D03*
X414894Y453432D03*
X419296Y449111D03*
X423572Y453454D03*
X419092Y457572D03*
X419225Y453324D03*
X410200Y474200D03*
X410179Y469769D03*
X416215Y512533D03*
X392315Y667333D03*
X375079Y654878D03*
X375718Y687266D03*
X430267Y679595D03*
X413860Y696428D03*
X400222Y683217D03*
X388817Y692040D03*
X409415Y735333D03*
X420252Y725194D03*
X420891Y757582D03*
X392551Y758648D03*
X403845Y742027D03*
X390207Y728816D03*
X361442Y736700D03*
X430906Y711983D03*
X402566Y713049D03*
X395450Y767846D03*
X378868Y723311D03*
X421530Y814262D03*
X419186Y784430D03*
X395515Y883833D03*
X429202Y894806D03*
X426858Y864974D03*
X382324Y863483D03*
X382963Y895871D03*
X365917Y880316D03*
X413927Y901690D03*
X397345Y857155D03*
X437915Y63033D03*
X432682Y23909D03*
X472315Y23056D03*
X496393Y55871D03*
X457399Y46069D03*
X496109Y93412D03*
X457989Y78967D03*
X493200Y145500D03*
X451789Y154565D03*
X484915Y271133D03*
X473097Y208901D03*
X453252Y250240D03*
X499500Y405382D03*
X438300Y481200D03*
X434515Y483333D03*
X434412Y479334D03*
X432014Y476132D03*
X460591Y484133D03*
X478515D03*
X486700Y485900D03*
X500000Y416969D03*
X483200Y512828D03*
X483402Y507800D03*
X464300Y519000D03*
X490900Y524700D03*
X491300Y553900D03*
X455846Y546626D03*
X442600Y503892D03*
X477115Y563733D03*
X465212Y726260D03*
X465851Y758648D03*
X437511Y759714D03*
X448805Y743093D03*
X435167Y729882D03*
X474587Y765253D03*
X445197Y719047D03*
X462315Y791333D03*
X449231Y780808D03*
X449870Y813196D03*
X432824Y797641D03*
X476931Y795085D03*
X488225Y778464D03*
X499945Y828325D03*
X486307Y815114D03*
X456903Y861352D03*
X457542Y893740D03*
X440496Y878185D03*
X488651Y844946D03*
X499208Y899795D03*
X463674Y852891D03*
X557547Y24335D03*
X526213Y34431D03*
X555558Y100229D03*
X531425Y77545D03*
X554515Y180233D03*
X545330Y147959D03*
X521476Y205704D03*
X509632Y174434D03*
X526688Y248818D03*
X537842Y407738D03*
X537500Y401600D03*
X529200Y388900D03*
X508500Y393600D03*
X506000Y486293D03*
X511015Y431233D03*
X525338Y523500D03*
X529800Y542200D03*
X525800Y535900D03*
X566000Y536700D03*
X508224Y580873D03*
X542615Y676933D03*
X549379Y653173D03*
X504632Y761631D03*
X505271Y794019D03*
X516352Y811492D03*
X562377Y833013D03*
X532332Y836635D03*
X516991Y843880D03*
X563016Y865401D03*
X534676Y866467D03*
X545970Y849846D03*
X545118Y880530D03*
X528711Y897363D03*
X515073Y884152D03*
X562590Y881808D03*
X510579Y854786D03*
X545757Y912918D03*
X517417Y913984D03*
X564934Y911640D03*
X621115Y55033D03*
X573457Y59531D03*
X621826Y20111D03*
X591122Y33010D03*
X607704Y77545D03*
X586385Y204283D03*
X596334Y173012D03*
X575015Y264733D03*
X602967Y248818D03*
X641400Y394600D03*
X633923Y520400D03*
X640200Y536400D03*
X587942Y582024D03*
X614582Y653599D03*
X604141Y675547D03*
X578784Y682152D03*
X582620Y653386D03*
X632693Y697281D03*
X575315Y730733D03*
X607550Y703460D03*
X628006Y720720D03*
X586415Y786233D03*
X577315Y881833D03*
X592635Y878186D03*
X576228Y895019D03*
X640791Y876268D03*
X641430Y908656D03*
X613090Y909722D03*
X624384Y893101D03*
X610746Y879890D03*
X593274Y910574D03*
X660180Y56547D03*
X657451Y28746D03*
X703700Y30300D03*
X651658Y95968D03*
X692985Y75650D03*
X699619Y201914D03*
X652714Y200019D03*
X692512Y162589D03*
X661673Y260892D03*
X688248Y246923D03*
X712386Y297542D03*
X653500Y394600D03*
X711500Y438300D03*
X702000Y485700D03*
X688615Y485133D03*
X694995Y453626D03*
X694923Y461253D03*
X694851Y469456D03*
X694907Y476993D03*
X644900Y538300D03*
X650700Y536600D03*
X660800Y539800D03*
X682015Y493633D03*
X668135Y523360D03*
X672161Y528021D03*
X676550Y523677D03*
X672342Y519560D03*
X672257Y523769D03*
X691200Y507800D03*
X644415Y560714D03*
X678293Y698772D03*
X675736Y657222D03*
X694061Y681726D03*
X654641Y691101D03*
X643987Y664041D03*
X697897Y662763D03*
X708231Y730948D03*
X681276Y722211D03*
X650805Y716671D03*
X698962Y707936D03*
X687315Y762233D03*
X685707Y778945D03*
X685215Y823933D03*
X685108Y855661D03*
X692356Y875629D03*
X692995Y908017D03*
X664655Y909083D03*
X675949Y892462D03*
X662311Y879251D03*
X754800Y56800D03*
Y36800D03*
Y16800D03*
X723466Y60810D03*
X721334Y17767D03*
X754800Y76800D03*
X754700Y117600D03*
Y97600D03*
X734333Y88085D03*
X727515Y179133D03*
X754700Y197600D03*
Y177600D03*
Y157600D03*
Y137600D03*
Y257600D03*
Y237600D03*
Y217600D03*
X746715Y331203D03*
X754700Y277600D03*
X753800Y303200D03*
X767300Y340400D03*
X766900Y333754D03*
X735134Y289819D03*
X767000Y410900D03*
X766700Y403500D03*
X766900Y395400D03*
Y387800D03*
Y364600D03*
Y356300D03*
X767600Y348500D03*
X767400Y481600D03*
Y465900D03*
X767500Y450800D03*
X767300Y441747D03*
X766500Y435100D03*
X766800Y427000D03*
X767100Y418700D03*
X747915Y541533D03*
X763510Y518353D03*
X758641Y524059D03*
X761015Y503960D03*
X754800Y546300D03*
X742400Y532597D03*
X741600Y541600D03*
X736000Y539500D03*
X738627Y545621D03*
X767100Y544600D03*
X766800Y535700D03*
X767200Y524500D03*
X766900Y497700D03*
X767200Y489700D03*
X746951Y525677D03*
X752515Y514433D03*
X760911Y539742D03*
X759100Y489500D03*
X761000Y552844D03*
X757000Y555900D03*
X742300Y569500D03*
X767100Y623900D03*
Y614800D03*
X766700Y606900D03*
X767700Y600200D03*
X766700Y592700D03*
X767000Y584300D03*
Y576100D03*
Y569500D03*
X760515Y560714D03*
X726000Y650700D03*
X720000Y650800D03*
X733000Y650600D03*
X740000D03*
X766900Y639500D03*
Y631900D03*
X715795Y697494D03*
X750300Y663000D03*
X740513Y687906D03*
X745733Y713048D03*
X764200Y813000D03*
X745413Y854763D03*
X716221Y876694D03*
X729859Y889905D03*
X718565Y906526D03*
X746905Y905460D03*
X746266Y873072D03*
X737062Y845433D03*
G54D50*
X134000Y52600D03*
Y77400D03*
X281963Y485753D03*
Y510553D03*
X340774Y65179D03*
Y40379D03*
X310274Y65179D03*
Y40379D03*
X343791Y395598D03*
X343292Y485604D03*
X312767Y485379D03*
X343791Y420398D03*
X323221Y445562D03*
Y470362D03*
X343292Y510404D03*
X312767Y510179D03*
X371274Y65179D03*
Y40379D03*
G54D41*
X33845Y507529D03*
Y499929D03*
X41797Y500609D03*
Y508209D03*
X99375Y144069D03*
Y151669D03*
X123397Y144069D03*
Y151669D03*
X115601Y144069D03*
Y151669D03*
X107672Y144069D03*
Y151669D03*
X174950Y133259D03*
X183700Y133300D03*
X183034Y162805D03*
Y170405D03*
X197209Y165797D03*
Y158197D03*
X174950Y140859D03*
X183700Y140900D03*
X205600Y165800D03*
Y158200D03*
X194877Y385099D03*
Y392699D03*
X187165Y385235D03*
Y392835D03*
X195311Y407990D03*
Y415590D03*
X215284Y382027D03*
Y389627D03*
X200959Y429749D03*
Y422149D03*
X197214Y464181D03*
Y456581D03*
X238000Y60400D03*
Y52800D03*
X263100Y60400D03*
Y52800D03*
X254900Y60400D03*
Y52800D03*
X246400Y60400D03*
Y52800D03*
X223321Y389661D03*
Y382061D03*
X254182Y496347D03*
Y503947D03*
X237203Y519878D03*
Y527478D03*
X261424Y519113D03*
Y526713D03*
X253508Y519183D03*
Y526783D03*
X238118Y504116D03*
Y496516D03*
X246132Y504110D03*
Y496510D03*
X262501Y504118D03*
Y496518D03*
X229241Y527601D03*
Y520001D03*
G54D32*
X73943Y205660D03*
Y213410D03*
X72930Y633923D03*
Y641673D03*
X65430Y637798D03*
X72814Y652628D03*
Y660378D03*
X65314Y656503D03*
X73412Y748676D03*
Y756426D03*
X65912Y752551D03*
X73356Y767193D03*
Y774943D03*
X65856Y771068D03*
X81443Y209535D03*
G54D23*
X45100Y89400D03*
X45200Y82900D03*
X72569Y219284D03*
X70277Y517540D03*
X59282Y521602D03*
X48002Y517237D03*
X63807Y647187D03*
X64298Y761923D03*
X149282Y164664D03*
X110971Y182699D03*
X84700Y141100D03*
X115141Y199000D03*
X117341Y194500D03*
X147610Y331731D03*
X136517Y335856D03*
X125273Y331655D03*
X136963Y517903D03*
X81425Y521698D03*
X92450Y517603D03*
X103504Y521857D03*
X114725Y517858D03*
X125800Y522071D03*
X147954Y522037D03*
X214222Y101900D03*
X203020Y93789D03*
X201664Y85481D03*
X203290Y102533D03*
X160361Y145062D03*
X159849Y176397D03*
X176482Y271928D03*
X176343Y267018D03*
X177356Y261409D03*
X175709Y256562D03*
X175577Y251228D03*
X175450Y246422D03*
X173990Y237502D03*
Y241702D03*
X176410Y281361D03*
X176443Y276656D03*
X176610Y294061D03*
X176510Y285561D03*
X176610Y289861D03*
X158681Y335850D03*
X180738Y344153D03*
X169685Y339913D03*
X214080Y356594D03*
X202938Y352449D03*
X191857Y348289D03*
X212100Y449700D03*
X189566Y485443D03*
Y489543D03*
X181104Y517848D03*
X158967Y517830D03*
X170087Y522020D03*
X214463Y521903D03*
X203263Y517803D03*
X192163Y522003D03*
X244790Y98033D03*
X223666Y218917D03*
X232758Y405205D03*
X249809Y403106D03*
X225139Y363907D03*
X242703Y428291D03*
X235199Y461252D03*
X235316Y473688D03*
X358000Y792962D03*
X342834Y792836D03*
X458763Y514834D03*
X466395D03*
X487437Y528628D03*
X487483Y537159D03*
X487213Y545645D03*
X487366Y489976D03*
X529300Y393000D03*
X645700Y394600D03*
X670009Y462023D03*
X653509Y478423D03*
X649409Y482723D03*
X665909Y466123D03*
X688300Y544300D03*
X732809Y478623D03*
X736909Y482823D03*
X720409Y466123D03*
X716309Y462023D03*
X747300Y546500D03*
X749500Y555900D03*
Y551800D03*
X749600Y577500D03*
X749530Y569233D03*
X749537Y560714D03*
X749629Y573387D03*
X725800Y853200D03*
G54D14*
G01X-771361Y-182763D02*
Y-262763D01*
G01Y-218263D02*
X373639D01*
G01X-771361Y-262763D02*
X373639D01*
G01X-775361Y-166763D02*
G02I-12000J0D01*
G01X-780511D02*
G02I-6850J0D01*
G01X-787361Y-182763D02*
Y-150763D01*
G01X-771361Y-166763D02*
X-803361D01*
G01X-771361Y-182763D02*
X373639D01*
G01X-413861D02*
Y-262763D01*
G01X-276361Y-182763D02*
Y-262763D01*
G01X-161361Y-182763D02*
Y-262763D01*
G01X6139Y-182763D02*
Y-262763D01*
G01X57200Y175300D02*
X55200Y177300D01*
X36000D01*
X34200Y179100D01*
Y200900D01*
X4250Y230850D01*
Y494945D01*
X21461Y512156D01*
X27359D01*
X31967Y516764D01*
X32026D01*
G01X48650Y82900D02*
X51200D01*
X51900Y83600D01*
G01X69800Y176800D02*
X69850Y176850D01*
Y180800D01*
G01X77250Y199800D02*
X73800D01*
X73700Y199700D01*
G01X43810Y172352D02*
X40348D01*
X39800Y172900D01*
G01X55624Y255132D02*
X55813Y254943D01*
Y251483D01*
G01Y258883D02*
Y255321D01*
X55624Y255132D01*
G01X62913Y272683D02*
X61083D01*
X59523Y271123D01*
G01X62913Y276783D02*
Y272683D01*
G01X55813Y267083D02*
Y263640D01*
X55883Y263570D01*
G01X59258Y246890D02*
X55696Y243328D01*
Y242114D01*
G01X63046Y285730D02*
Y281630D01*
G01D02*
X59823D01*
X59523Y281330D01*
G01X55413Y276783D02*
X52391D01*
X52257Y276649D01*
G01X55413Y285083D02*
Y288649D01*
X55420Y288656D01*
G01X47230Y373862D02*
X43820D01*
X43639Y374043D01*
G01X51729Y521570D02*
Y517514D01*
X51452Y517237D01*
G01D02*
Y514620D01*
X51383Y514551D01*
Y514037D01*
G01X62772Y517540D02*
Y513528D01*
X63862Y512438D01*
G01X62732Y521602D02*
Y517580D01*
X62772Y517540D01*
G01X73727D02*
Y514525D01*
X73542Y514340D01*
G01X73792Y521666D02*
Y517605D01*
X73727Y517540D01*
G01X59384Y641151D02*
Y644782D01*
X59379Y644787D01*
G01X62340Y665912D02*
X60812D01*
X57500Y662600D01*
G01X52900Y645300D02*
X47000D01*
G01X67257Y647187D02*
Y643668D01*
G01X72930Y641673D02*
Y645818D01*
G01X73900Y664900D02*
X72814Y663814D01*
Y660378D01*
G01X79967Y643544D02*
X79656D01*
X77000Y646200D01*
G01X60122Y751011D02*
Y747800D01*
G01X64000Y765600D02*
X60700D01*
X59800Y764700D01*
G01X52900Y748300D02*
X52300D01*
X50000Y746000D01*
X47100D01*
G01X73325Y760926D02*
X73412Y760839D01*
Y756426D01*
G01X67748Y761923D02*
Y758251D01*
X67809Y758190D01*
G01X73282Y778907D02*
X73356Y778833D01*
Y774943D01*
G01X87791Y203800D02*
X87555Y204036D01*
X84641D01*
G01X149232Y164664D02*
X148109D01*
X145400Y161955D01*
G01X95491Y203600D02*
Y205900D01*
X94600Y206791D01*
Y206900D01*
G01X144950Y177338D02*
X145342Y177730D01*
X148551D01*
X149431Y176850D01*
G01D02*
X149861D01*
X153061Y173650D01*
Y172262D01*
G01X88150Y141100D02*
Y149103D01*
X85713Y151540D01*
G01X91178Y211383D02*
X94423D01*
X94548Y211258D01*
G01X148150Y233900D02*
X153400D01*
X156800Y230500D01*
G01X140103Y331742D02*
X139967Y331878D01*
Y335856D01*
G01X140103Y328216D02*
Y331742D01*
G01X117505Y331729D02*
Y335113D01*
X117460Y335158D01*
G01X128967Y335856D02*
Y339467D01*
X128964Y339470D01*
G01X128723Y331655D02*
Y335612D01*
X128967Y335856D01*
G01X151102Y335814D02*
Y336046D01*
X148782Y338366D01*
X148102D01*
G01X118175Y517858D02*
Y521953D01*
X118301Y522079D01*
G01D02*
Y524836D01*
X118744Y525279D01*
G01X140413Y517903D02*
Y521989D01*
X140462Y522038D01*
G01D02*
Y525175D01*
X140399Y525238D01*
G01X129413Y517903D02*
Y521908D01*
X129250Y522071D01*
G01D02*
Y525220D01*
X129199Y525271D01*
G01X107157Y517857D02*
Y521654D01*
X106954Y521857D01*
G01X107103Y525057D02*
Y522006D01*
X106954Y521857D01*
G01X95900Y517603D02*
Y521791D01*
X95935Y521826D01*
G01D02*
Y524690D01*
X95599Y525026D01*
G01X84875Y521698D02*
Y524822D01*
X84799Y524898D01*
G01X84912Y517603D02*
X84875Y517640D01*
Y521698D01*
G01X80191Y647837D02*
X85600D01*
G01X80653Y758697D02*
X84515D01*
X84703Y758885D01*
G01X80464Y764756D02*
X84059D01*
X84182Y764879D01*
G01X176139Y-182763D02*
Y-262763D01*
G01X168300Y111500D02*
X173300Y116500D01*
X196567D01*
X199611Y113456D01*
G01X217113Y130810D02*
Y122287D01*
X219600Y119800D01*
X380175D01*
X381025Y120650D01*
G01X220100Y123600D02*
X221124Y124624D01*
Y130726D01*
X221100Y130750D01*
G01X205114Y85481D02*
X205628Y85995D01*
Y89404D01*
G01X212700Y129500D02*
Y125900D01*
X212800Y125800D01*
G01X152350Y131084D02*
X156863Y135597D01*
X166149D01*
X166649Y136097D01*
G01X200100Y101200D02*
Y100648D01*
X202695Y98053D01*
X202975D01*
G01X217672Y101900D02*
X217909Y102137D01*
Y106010D01*
G01D02*
Y110100D01*
G01X217740Y98033D02*
Y101832D01*
X217672Y101900D01*
G01X160311Y145062D02*
Y141680D01*
G01X155600Y139000D02*
X157631D01*
X160311Y141680D01*
G01X177087Y178920D02*
X178700Y180533D01*
X182267D01*
X184900Y177900D01*
Y175500D01*
X183034Y173634D01*
Y170405D01*
G01X177087Y175483D02*
Y178920D01*
G01X168353Y140240D02*
X166649Y138536D01*
Y136097D01*
G01X153061Y172262D02*
X156610D01*
X157113Y171759D01*
G01X179793Y267018D02*
X182205D01*
X183120Y266103D01*
G01X179159Y256562D02*
X179797Y256609D01*
X182351D01*
X182853Y256107D01*
G01X180806Y261409D02*
X183610D01*
X183653Y261452D01*
X183956D01*
G01X219655Y214548D02*
X219692Y214585D01*
X223652D01*
G01X179027Y251228D02*
X179092Y251208D01*
X182177D01*
G01X183707Y289861D02*
X180060D01*
G01X173188Y344153D02*
Y348142D01*
X173508Y348462D01*
G01X173135Y339913D02*
Y344100D01*
X173188Y344153D01*
G01X184307Y348289D02*
Y344272D01*
X184188Y344153D01*
G01D02*
Y340638D01*
G01X162131Y335850D02*
Y332654D01*
X162135Y332650D01*
G01Y339913D02*
X162131Y339909D01*
Y335850D01*
G01X151060Y331731D02*
Y335772D01*
X151102Y335814D01*
G01X185315Y410483D02*
X182583D01*
X181576Y409476D01*
Y407810D01*
G01X185215Y414583D02*
X185415Y414383D01*
Y410583D01*
X185315Y410483D01*
G01X216178Y411331D02*
X217363Y410146D01*
Y407578D01*
G01X212492Y408833D02*
X214990Y411331D01*
X216178D01*
G01X217143Y418666D02*
Y416537D01*
X219144Y414536D01*
G01X195388Y352449D02*
Y355568D01*
X195307Y355649D01*
G01Y348289D02*
Y352368D01*
X195388Y352449D01*
G01X206430Y356594D02*
X206388Y356552D01*
Y352449D01*
G01D02*
Y349341D01*
X206775Y348954D01*
G01X217530Y356594D02*
Y363809D01*
X217635Y363914D01*
G01D02*
X215974D01*
X214660Y362600D01*
G01X182378Y390377D02*
X184836Y392835D01*
X187165D01*
G01X203410Y394323D02*
X201201Y392114D01*
X200498D01*
G01X207141Y392559D02*
X205174D01*
X203410Y394323D01*
G01X200498Y392114D02*
X199913Y392699D01*
X194877D01*
G01X185934Y476029D02*
X184619D01*
X178032Y482616D01*
X177588D01*
G01X215006Y438201D02*
Y436207D01*
X213400Y434601D01*
G01X185614Y458681D02*
X185814Y458481D01*
X190714D01*
G01X181980Y458681D02*
X185614D01*
G01X213982Y427789D02*
Y425618D01*
X217143Y422457D01*
Y418666D01*
G01X222900Y463100D02*
X220971Y461171D01*
X219011D01*
G01X190765Y470128D02*
X197221D01*
X200511Y473418D01*
X200788D01*
G01X218984Y464704D02*
Y465731D01*
X216619Y468096D01*
X209610D01*
X208873Y468833D01*
X204152D01*
X202600Y470385D01*
Y471606D01*
X200788Y473418D01*
G01X219011Y461171D02*
Y464677D01*
X218984Y464704D01*
G01X194624Y427263D02*
X187738D01*
X185828Y425353D01*
X182907D01*
X180445Y422891D01*
Y422567D01*
G01X176991Y463723D02*
X177414Y463300D01*
X181300D01*
G01X197214Y464181D02*
X191014D01*
X190714Y464481D01*
G01X203439Y465152D02*
X198185D01*
X197214Y464181D01*
G01X207834Y465346D02*
X207640Y465152D01*
X203439D01*
G01X185614Y464681D02*
X184233Y463300D01*
X181300D01*
G01X190714Y464481D02*
X190514Y464681D01*
X185614D01*
G01X211243Y462005D02*
X211415Y461833D01*
X214849D01*
X215511Y461171D01*
G01D02*
Y462037D01*
X215484Y462064D01*
Y464704D01*
G01X184554Y517848D02*
Y521944D01*
X184613Y522003D01*
G01D02*
Y524989D01*
X184399Y525203D01*
G01X195613Y517803D02*
Y522003D01*
G01D02*
Y525089D01*
X195499Y525203D01*
G01X206813Y522003D02*
Y525089D01*
X206699Y525203D01*
G01X206713Y517803D02*
Y521903D01*
X206813Y522003D01*
G01X162417Y517830D02*
Y521982D01*
X162455Y522020D01*
G01D02*
Y524795D01*
X162615Y524955D01*
Y525220D01*
G01X173599Y517848D02*
Y521958D01*
X173537Y522020D01*
G01D02*
Y525220D01*
G01X151404Y522037D02*
Y524978D01*
X151684Y525258D01*
G01X151424Y517879D02*
Y522017D01*
X151404Y522037D01*
G01X222577Y522319D02*
Y520885D01*
X219524Y517832D01*
X219492D01*
G01X201142Y837191D02*
X200932Y837401D01*
X194548D01*
G01X201663Y827680D02*
X201391Y827952D01*
X194548D01*
G01Y846849D02*
X200798D01*
G01X248096Y77735D02*
X248176Y77815D01*
X362793D01*
G01X225002Y130766D02*
Y128198D01*
X227104Y126096D01*
X362793D01*
G01X221409Y106010D02*
X232615D01*
G01X246455Y106307D02*
X246158Y106010D01*
X232615D01*
G01X248240Y102533D02*
Y104522D01*
X246455Y106307D01*
G01X250165Y93933D02*
X250288Y94056D01*
X252237D01*
X254887Y96706D01*
Y99526D01*
X251880Y102533D01*
X248240D01*
G01Y98033D02*
X251687D01*
G01X258530Y81976D02*
X259276Y81230D01*
X261830D01*
G01X244596Y77735D02*
X244602Y77729D01*
Y73668D01*
G01X248102D02*
X248182Y73748D01*
X381025D01*
G01X246665Y93933D02*
X243433D01*
X242800Y93300D01*
G01X244740Y102533D02*
Y98033D01*
G01X231350Y222067D02*
Y217658D01*
G01X257400Y403206D02*
X257300Y403106D01*
X253259D01*
G01X236208Y405205D02*
X239205D01*
X239600Y405600D01*
G01X238000Y414650D02*
Y411400D01*
X237800Y411200D01*
G01X226576Y401835D02*
X226428Y401687D01*
Y398491D01*
G01X241728Y367706D02*
X244494D01*
X244515Y367685D01*
X244928D01*
G01X237455Y367805D02*
X241629D01*
X241728Y367706D01*
G01Y356706D02*
X238765D01*
X238151Y356092D01*
G01X228589Y363907D02*
X228510Y367624D01*
G01X237455Y378805D02*
X239187D01*
X240715Y380333D01*
G01X222254Y398399D02*
X222269Y398807D01*
Y402278D01*
G01X222254Y394899D02*
X226336D01*
X226428Y394991D01*
G01D02*
X228600Y392819D01*
Y390796D01*
X229500Y389896D01*
X233884D01*
X236637Y387143D01*
G01X239693Y396029D02*
X239586Y396136D01*
X234222D01*
G01X236637Y383643D02*
X236646Y383634D01*
X240662D01*
G01D02*
X242066D01*
X245000Y380700D01*
G01X242473Y468923D02*
X243843Y469043D01*
X246502Y471702D01*
Y472752D01*
G01X241556Y478217D02*
X243983D01*
X246500Y475700D01*
Y472754D01*
X246502Y472752D01*
G01X250500Y461100D02*
X255205Y461115D01*
X255622Y461532D01*
G01X246800Y440050D02*
X250350D01*
X250400Y440000D01*
G01X246153Y428291D02*
X249409D01*
X249600Y428100D01*
G01X237550Y454700D02*
Y457850D01*
X237700Y458000D01*
G01X226992Y464033D02*
X223833D01*
X222900Y463100D01*
G01X231108Y464087D02*
Y462208D01*
X229600Y460700D01*
G01X242700Y440050D02*
X239250D01*
X239000Y440300D01*
G01X246147Y432409D02*
X249509D01*
X249600Y432500D01*
G01X241050Y454700D02*
X244600D01*
X244800Y454500D01*
G01X238118Y496516D02*
Y492166D01*
G01X246132Y496510D02*
Y492160D01*
G01X271970Y794774D02*
Y798668D01*
G01X282292Y794780D02*
Y798289D01*
X282413Y798410D01*
G01X228021Y787335D02*
Y790739D01*
X230515Y793233D01*
G01X223596Y782163D02*
X223449Y782016D01*
Y778667D01*
G01X226949D02*
Y782735D01*
G01X277970Y794774D02*
Y817347D01*
X276982Y818335D01*
G01D02*
Y828335D01*
G01D02*
Y845343D01*
X277254Y845615D01*
G01Y849115D02*
Y852624D01*
G01X346284Y792836D02*
Y796159D01*
X346510Y796385D01*
G01X350477Y792923D02*
Y796097D01*
X350765Y796385D01*
G01X315665Y795010D02*
Y798414D01*
X315696Y798445D01*
G01X294126Y794808D02*
Y798525D01*
X294148Y798547D01*
G01X305449Y794862D02*
Y798193D01*
X305437Y798205D01*
G01X373639Y-182763D02*
Y-262763D01*
G01X401639Y-166763D02*
G02I-12000J0D01*
G01X396489D02*
G02I-6850J0D01*
G01X389639Y-182763D02*
Y-150763D01*
G01X405639Y-166763D02*
X373639D01*
G01X381025Y120650D02*
X722687D01*
G01X361450Y792962D02*
Y796193D01*
X361814Y796557D01*
G01X501800Y387600D02*
X503900Y389700D01*
X504650D01*
G01X506000Y486293D02*
X504907Y485200D01*
X497600D01*
X492824Y489976D01*
X490816D01*
G01X457091Y490002D02*
Y486699D01*
G01X460591Y484133D02*
Y490002D01*
G01X478515Y484133D02*
X478737Y484355D01*
Y490049D01*
G01X486700Y485900D02*
X487316Y486516D01*
Y489976D01*
G01X487388Y541335D02*
X483957D01*
X483530Y541762D01*
G01X487073Y549911D02*
Y554094D01*
G01X487380Y532955D02*
X484397D01*
X482183Y535169D01*
G01X487253Y501502D02*
X487273Y501482D01*
Y497927D01*
G01D02*
X485610D01*
X483008Y500529D01*
G01X469845Y514834D02*
Y517860D01*
X469932Y517947D01*
Y518034D01*
G01X447368Y508324D02*
Y511829D01*
X447307Y511890D01*
G01X447090Y500392D02*
Y497242D01*
G01X475237Y490049D02*
X471410D01*
G01X442600Y503892D02*
X447090D01*
G01D02*
X451082D01*
X451123Y503933D01*
G01X460591Y490002D02*
X460470Y490123D01*
Y493874D01*
G01X478678Y493916D02*
Y490108D01*
X478737Y490049D01*
G01X487316Y489976D02*
X487268Y490024D01*
Y494161D01*
G01X526700Y397400D02*
X525200D01*
X523200Y399400D01*
G01X501750Y380000D02*
X506100D01*
G01X514000Y486293D02*
X506000D01*
G01X536736Y418540D02*
X536621Y418425D01*
X530634D01*
G01X517502Y552477D02*
Y548968D01*
X517663Y548807D01*
G01X514073Y552477D02*
X517502D01*
G01X688950Y537000D02*
Y540000D01*
X688800Y540150D01*
Y540450D01*
G01X684600Y542100D02*
Y533800D01*
X682986Y532186D01*
G01X664700Y543250D02*
Y544800D01*
X662200Y547300D01*
G01X696100Y536200D02*
Y542300D01*
X694100Y544300D01*
X691750D01*
G01X693389Y759399D02*
X691215D01*
X690105Y758289D01*
X689945D01*
G01X693442Y762972D02*
Y759452D01*
X693389Y759399D01*
G01X697925Y820842D02*
X702211D01*
X702290Y820921D01*
G01X697977Y817304D02*
Y820790D01*
X697925Y820842D01*
G01X767300Y340400D02*
X769095Y338605D01*
X780514D01*
G01X767600Y348500D02*
Y348700D01*
X769500Y350600D01*
X780329D01*
X780514Y350415D01*
G01X766900Y356300D02*
X768850Y354350D01*
X780514D01*
G01X766900Y364600D02*
X768465Y366165D01*
X780514D01*
G01X766900Y387800D02*
X768885Y389785D01*
X780514D01*
G01X766900Y395400D02*
X768580Y393720D01*
X780514D01*
G01X766700Y403500D02*
X768735Y405535D01*
X780514D01*
G01X767000Y410900D02*
X768430Y409470D01*
X780514D01*
G01X767700Y473300D02*
X768540Y472460D01*
X780514D01*
G01X768000Y457700D02*
X768985Y456715D01*
X780514D01*
G01X767100Y418700D02*
X769680Y421280D01*
X780514D01*
G01X766800Y427000D02*
X768580Y425220D01*
X780514D01*
G01X766500Y435100D02*
X768430Y437030D01*
X780514D01*
G01X767300Y441747D02*
X768082Y440965D01*
X780514D01*
G01X767500Y450800D02*
X768000D01*
X769975Y452775D01*
X780514D01*
G01X767400Y465900D02*
X770025Y468525D01*
X780514D01*
G01X767400Y481600D02*
X770075Y484275D01*
X780514D01*
G01X767200Y489700D02*
X768690Y488210D01*
X780514D01*
G01X766900Y497700D02*
X769220Y500020D01*
X780514D01*
G01X767200Y524500D02*
X768055Y523645D01*
X780514D01*
G01X766800Y535700D02*
X767045Y535455D01*
X780514D01*
G01X767000Y576100D02*
X768275Y574825D01*
X780514D01*
G01X767000Y584300D02*
X769335Y586635D01*
X780514D01*
G01X766700Y592700D02*
X768825Y590575D01*
X780514D01*
G01X767700Y600200D02*
X769885Y602385D01*
X780514D01*
G01X766700Y606900D02*
X767280Y606320D01*
X780514D01*
G01X767100Y614800D02*
X770430Y618130D01*
X780514D01*
G01X767100Y623900D02*
X768930Y622070D01*
X780514D01*
G01X766504Y649630D02*
X780514D01*
G01Y633880D02*
X768880D01*
G01D02*
X766900Y631900D01*
G01X780514Y637815D02*
X772815D01*
X768880Y633880D01*
G01X780514Y657500D02*
X769941D01*
X766006Y653565D01*
G01D02*
X779564D01*
G01X729250Y853200D02*
Y850000D01*
X8789Y376072D03*
X6944Y414616D03*
X6855Y436844D03*
X6750Y425868D03*
X7180Y449205D03*
X72838Y388509D03*
X68901D03*
X72838Y392446D03*
X68901D03*
X64964D03*
X72838Y396383D03*
X68901D03*
X64964D03*
X62439Y413744D03*
X66931Y398350D03*
X74863Y390483D03*
X64055Y389700D03*
X33722Y401639D03*
X74544Y414071D03*
X70779Y402387D03*
X79016Y410283D03*
X35738Y406956D03*
X14422Y411528D03*
X14657Y416838D03*
X10615Y411073D03*
X26551Y394546D03*
X30232Y416556D03*
X23922Y415548D03*
X35994Y410146D03*
X43719Y414419D03*
X32141Y407501D03*
X31808Y410684D03*
X18448Y402542D03*
X74817Y409752D03*
X26972Y399588D03*
X70882Y409794D03*
X66938Y410045D03*
X78939Y414083D03*
X18448Y406788D03*
X53976Y389814D03*
X74894Y398251D03*
X62031Y399713D03*
X70775Y398396D03*
X70845Y405839D03*
X70952Y414050D03*
X54515Y396433D03*
X54463Y386651D03*
X70865Y390502D03*
X74702Y394300D03*
X74869Y406315D03*
X78300Y386505D03*
X64948Y386626D03*
X78362Y398337D03*
X77963Y381183D03*
X70888Y394222D03*
X66963Y473083D03*
X66931Y484968D03*
X79081Y465348D03*
X70704Y429620D03*
X67015Y449433D03*
X74639Y441855D03*
X78754Y453353D03*
X78811Y426113D03*
X52151Y456887D03*
X66903Y457689D03*
X78798Y433983D03*
X17072Y435057D03*
X74836Y453477D03*
X59980Y482517D03*
X78754Y449904D03*
X67112Y481066D03*
X70488Y465291D03*
X74450Y457429D03*
X70713Y461504D03*
X36237Y441728D03*
X70908Y457771D03*
X70898Y418271D03*
X61038Y424878D03*
X74726Y425594D03*
X59209Y438908D03*
X46853Y441796D03*
X78561Y421756D03*
X70809Y438057D03*
X43659Y432766D03*
X43088Y438073D03*
X45486Y456341D03*
X38566Y451290D03*
X42312Y463368D03*
X74780Y429794D03*
X24357Y423051D03*
X37988Y438328D03*
X19757Y418538D03*
X29472Y428016D03*
X78738Y429679D03*
X11964Y421332D03*
X52476Y439395D03*
X13062Y429279D03*
X74656Y421838D03*
X17936Y431103D03*
X14206Y433632D03*
X15424Y422722D03*
X70857Y433857D03*
X19015Y426461D03*
X14147Y438989D03*
X74752Y437655D03*
X74437Y473159D03*
X15872Y441916D03*
X74460Y461287D03*
X78793Y445704D03*
X70868Y477094D03*
X23748Y436249D03*
X26611Y441743D03*
X70909Y469595D03*
X30513Y437850D03*
X74702Y469183D03*
X37420Y461517D03*
X31517Y445328D03*
X70868Y473157D03*
X28472Y447107D03*
X48298Y454813D03*
X70602Y453533D03*
X79050Y457367D03*
X74805Y481031D03*
X66991Y476766D03*
X62798Y461555D03*
X74451Y465323D03*
X79094Y441620D03*
X74801Y433368D03*
X70869Y421840D03*
X70759Y449277D03*
X74805Y477094D03*
X70868Y481031D03*
X74598Y485021D03*
X78421Y473078D03*
X74695Y449260D03*
X59063Y485583D03*
X79134Y461339D03*
X68901Y486935D03*
Y494809D03*
X72838D03*
X64964Y490872D03*
X68901D03*
X72838D03*
X64964Y486935D03*
X72838D03*
X78742Y488905D03*
X66961Y488885D03*
X74805Y492842D03*
X74870Y488789D03*
X69523Y567387D03*
X69555Y564187D03*
X69569Y594959D03*
X69520Y560987D03*
X68421Y570392D03*
X69323Y579887D03*
X69518Y604727D03*
X69599Y601527D03*
X69569Y598159D03*
X69388Y576660D03*
X69450Y573460D03*
X69569Y608021D03*
X69496Y611417D03*
X69661Y591387D03*
X66579Y592250D03*
X63125Y592801D03*
X62681Y589462D03*
X69451Y684303D03*
Y681103D03*
X68928Y687846D03*
X69316Y697605D03*
X69451Y691003D03*
X69474Y694403D03*
X69523Y718313D03*
Y715113D03*
X69472Y729385D03*
X69548Y726185D03*
X69558Y711913D03*
X68620Y722610D03*
X106419Y310245D03*
X126184Y310860D03*
X93200Y308800D03*
X145771Y414191D03*
X82555Y406288D03*
X110472Y394496D03*
X145765Y406438D03*
X122053Y406224D03*
X114175Y410161D03*
X125990Y394413D03*
X141738D03*
X98427Y414098D03*
X125990D03*
X90553Y410161D03*
X102263Y414083D03*
X141887Y410202D03*
X102364Y406224D03*
X133864Y410161D03*
X94367Y394479D03*
X102364Y402287D03*
X106301Y398350D03*
Y402287D03*
X102364Y398350D03*
X110238Y402287D03*
X114175D03*
X110238Y398350D03*
X114175D03*
X85721Y385798D03*
X149362Y413951D03*
X149498Y406396D03*
X145795Y410173D03*
X149431Y394402D03*
X149783Y390487D03*
X110238Y410161D03*
X141738Y414098D03*
X133863Y413773D03*
X114175Y414098D03*
X122053D03*
X125990Y410161D03*
X94579Y406324D03*
X118130Y398511D03*
X98427Y410161D03*
X90553Y414098D03*
X86563Y402383D03*
X133964Y394555D03*
X102555Y394412D03*
X86616Y394413D03*
X86463Y390483D03*
X114175Y406224D03*
X126063Y406183D03*
X141738Y406224D03*
X106301D03*
X149663Y410083D03*
X82459Y413976D03*
X90566Y394383D03*
X82663Y402406D03*
X133864Y402287D03*
X86772Y414047D03*
X122053Y402287D03*
X133864Y398350D03*
X137801D03*
X122053D03*
X137801Y402287D03*
X125990D03*
Y398350D03*
X129927Y402287D03*
Y398350D03*
X82663Y398383D03*
X141738Y402287D03*
Y398350D03*
X145865Y402287D03*
Y398350D03*
X149488Y402114D03*
X149583Y398383D03*
X90359Y469275D03*
X137801Y453472D03*
Y445598D03*
X133864Y437720D03*
Y445598D03*
X133953Y425813D03*
X102684Y445671D03*
X106263Y437583D03*
X133864Y433783D03*
X102364Y429846D03*
X98363Y421883D03*
X94263Y418129D03*
X106210Y421976D03*
X110332Y425814D03*
X149612Y445598D03*
Y433783D03*
X86493Y441401D03*
X86616Y433783D03*
X86687Y421669D03*
X137801Y477094D03*
X149612D03*
X114175D03*
X102364D03*
X98626Y477049D03*
X130081Y425912D03*
X121943Y425834D03*
X114091Y425962D03*
X122053Y421972D03*
Y418035D03*
X106301D03*
X114175D03*
X133863Y417883D03*
X117951Y437592D03*
X114175Y445598D03*
X110263Y441683D03*
X118189Y445711D03*
X125990Y445598D03*
X110238Y437720D03*
X125990D03*
X110222Y417989D03*
X106341Y426062D03*
X82564Y449659D03*
X145663Y441483D03*
X98288Y441609D03*
X149612Y429846D03*
X110238Y453472D03*
X122053Y429846D03*
X114063Y429879D03*
X125897Y453240D03*
X118238Y453417D03*
X149594Y480923D03*
X94518Y449186D03*
X86768Y449383D03*
X98427Y484968D03*
Y481031D03*
X102364D03*
Y484968D03*
X106301D03*
Y481031D03*
X114175Y484968D03*
Y481031D03*
X122053Y484968D03*
Y481031D03*
X125990Y484968D03*
Y481031D03*
X145567Y453547D03*
X145763Y449583D03*
X149576Y465497D03*
X98597Y457291D03*
X94490Y429846D03*
X90463Y425983D03*
X90480Y437608D03*
X82562Y425980D03*
X86505Y425987D03*
X90380Y429650D03*
X130080Y457372D03*
X94490Y437720D03*
X82681Y430041D03*
X141827Y461346D03*
X98334Y429754D03*
X98427Y437720D03*
X94369Y425977D03*
X82677Y433595D03*
X149563Y469220D03*
X94490Y433783D03*
X141738Y481031D03*
X82663Y457486D03*
X141738Y484968D03*
X98433Y449125D03*
X137801Y481031D03*
X102600Y425983D03*
X137801Y484968D03*
X94554Y421911D03*
X133864Y481031D03*
X149612Y437720D03*
X94414Y445605D03*
X133864Y484968D03*
X86663Y429536D03*
X82542Y445403D03*
X98427Y433783D03*
X86568Y445669D03*
X90426Y449431D03*
X90563Y417983D03*
X145675Y425909D03*
X82573Y441360D03*
X145675Y437720D03*
X98280Y445405D03*
X90426Y441880D03*
X145675Y481031D03*
Y484968D03*
X145737Y418077D03*
X145675Y473157D03*
Y465283D03*
X149719Y457328D03*
X129927Y473157D03*
Y465283D03*
X137801Y461346D03*
Y457409D03*
X114175Y473157D03*
X122053Y469220D03*
X110263Y469083D03*
X122053Y473157D03*
X90350Y473069D03*
X82679Y477094D03*
X90662Y461604D03*
X106263Y453483D03*
X106449Y465157D03*
X122053Y445598D03*
X126180Y418224D03*
X137801Y437720D03*
X137767Y425993D03*
X129927Y445598D03*
X141738Y449535D03*
X133864Y421972D03*
Y429846D03*
X98533Y418180D03*
X118134Y449362D03*
X106363Y441583D03*
X110238Y445598D03*
X110289Y422113D03*
X122053Y437720D03*
X114175D03*
X94661Y441681D03*
X106263Y433683D03*
X90544Y433408D03*
X90408Y421930D03*
X129927Y437720D03*
X141738Y429846D03*
X86663Y453583D03*
X82732Y453139D03*
X102227Y473344D03*
X145675Y469220D03*
X90376Y476918D03*
X110238Y477094D03*
X141738D03*
X137801Y473157D03*
X98427Y469046D03*
X106301Y469220D03*
X114175D03*
X126057Y469287D03*
X129927Y469220D03*
X137801D03*
X122053Y465283D03*
X133864D03*
X106301Y461346D03*
X122113Y457535D03*
X129963Y461283D03*
X110263Y457283D03*
X122158Y453388D03*
X125990Y477094D03*
X137801Y449535D03*
X149612Y425909D03*
X82535Y461227D03*
X83021Y473118D03*
X141595Y421932D03*
X141775Y426153D03*
X86735Y461382D03*
X141763Y437883D03*
X86937Y477160D03*
X141682Y417902D03*
X82759Y469436D03*
X145663Y445583D03*
X145675Y429846D03*
X142008Y457429D03*
X141863Y445583D03*
X86959Y469276D03*
X137570Y421843D03*
X145561Y421879D03*
X90965Y465270D03*
X129927Y481031D03*
Y484968D03*
X110238Y481031D03*
Y484968D03*
X94490Y481031D03*
X86663Y457283D03*
X94490Y484968D03*
X86765Y465205D03*
X138061Y418151D03*
X145675Y433783D03*
X82763Y417750D03*
X86523Y417943D03*
X94844Y469182D03*
X102469Y469134D03*
X106149Y457371D03*
X141649Y453189D03*
X149620Y485149D03*
X98682Y461441D03*
X94092Y492819D03*
X141738Y488905D03*
X110238D03*
X125990D03*
X94377Y489070D03*
X118004Y488825D03*
X133864Y488905D03*
X149612D03*
X102308Y488978D03*
X86616Y488905D03*
X91852Y563129D03*
X91156Y572112D03*
X90823Y581387D03*
X91343Y598284D03*
X91023Y606587D03*
X90923Y616187D03*
X91198Y595087D03*
X91123Y591887D03*
X91223Y588487D03*
X159768Y238444D03*
X160004Y233894D03*
X167327Y388509D03*
X163390D03*
X171264Y392446D03*
X167327D03*
X163390D03*
X171264Y396383D03*
X167327D03*
X163390D03*
X181576Y407810D03*
X175463Y413760D03*
X161499Y402554D03*
X169297Y402536D03*
X157502Y390427D03*
X173425Y390228D03*
X214660Y362600D03*
X176751Y387090D03*
X157251Y414149D03*
X161477Y394511D03*
X180991Y398678D03*
X180809Y414170D03*
X179225Y403667D03*
X203410Y394323D03*
X182378Y390377D03*
X157574Y394185D03*
X161241Y398226D03*
X161277Y414114D03*
X174124Y402624D03*
X161213Y390551D03*
X169503Y386977D03*
X153587Y406496D03*
X157554Y402251D03*
X157698Y406313D03*
X161475Y410299D03*
X165266Y409882D03*
X165337Y414489D03*
X153528Y410052D03*
X165455Y398256D03*
X165229Y402019D03*
X157411Y398513D03*
X169113Y398299D03*
X178031Y390023D03*
X177588Y482616D03*
X161423Y469220D03*
X153583Y461058D03*
X169297Y477094D03*
Y465283D03*
X157486Y437720D03*
Y429846D03*
X153416Y445539D03*
X169290Y417960D03*
X169297Y437720D03*
X169112Y453260D03*
X169166Y429679D03*
X153549Y429846D03*
X165621Y418066D03*
X153549Y425909D03*
X161746Y421972D03*
X177182Y467018D03*
X175477Y472360D03*
X176815Y479061D03*
X161473Y457213D03*
X165360Y477094D03*
X153549Y437720D03*
X157560Y445484D03*
X153549Y449535D03*
X174859Y469220D03*
X157322Y453385D03*
X165317Y461561D03*
X165360Y473157D03*
X161455Y453385D03*
X177763Y486293D03*
X153463Y453383D03*
X157411Y469344D03*
X161423Y477094D03*
X157486Y461346D03*
X153690Y469111D03*
X165411Y429590D03*
X175161Y434723D03*
X161423Y445598D03*
X153549Y421972D03*
X161423Y484968D03*
Y481031D03*
X157486Y473157D03*
X165360Y469220D03*
X153549Y477094D03*
X173234Y465283D03*
Y453472D03*
X174086Y484839D03*
X175150Y476294D03*
X174351Y429014D03*
X161423Y437720D03*
X153549Y433783D03*
X161363Y425780D03*
X173234Y437720D03*
X173155Y417978D03*
X153422Y441722D03*
X161423Y449430D03*
X153549Y473157D03*
X161670Y418161D03*
X176662Y418122D03*
X153201Y418097D03*
X157401Y418143D03*
X157463Y421883D03*
X157486Y425909D03*
X173458Y457178D03*
X178053Y474260D03*
X174601Y481467D03*
X165319Y453134D03*
X165353Y480812D03*
X157486Y433783D03*
X165360Y421972D03*
X153646Y457393D03*
X161294Y461561D03*
X165363Y425783D03*
X157393Y457572D03*
X165217Y457361D03*
X165355Y433382D03*
X161423Y473157D03*
X165355Y437582D03*
X165360Y445598D03*
X157411Y449556D03*
X169157Y445598D03*
X157508Y480990D03*
X165288Y449306D03*
X157486Y484968D03*
X153601Y480894D03*
X153586Y485118D03*
X161423Y433783D03*
X171264Y486935D03*
X167327D03*
X163390D03*
X171264Y490872D03*
X167327D03*
X163390D03*
X167327Y494809D03*
X163390D03*
X181414Y490281D03*
X174475Y488016D03*
X178084Y493198D03*
X157486Y488905D03*
X165360D03*
X169297Y492842D03*
X161423D03*
X159589Y817543D03*
X157422Y825918D03*
X158725Y835536D03*
X159688Y832484D03*
X159431Y838974D03*
X159688Y829234D03*
X159137Y820712D03*
X160735Y857183D03*
X154730Y847010D03*
X159688Y851564D03*
X159560Y842172D03*
X159426Y848357D03*
X651000Y467700D03*
X646163Y482677D03*
X643296Y477617D03*
X643914Y470592D03*
X648652Y470028D03*
X654990Y463513D03*
X658399Y460842D03*
X659485Y455066D03*
X666818Y452921D03*
X710645Y447266D03*
X678767Y447136D03*
X672583Y467901D03*
X667831Y479556D03*
X662166Y456914D03*
X661760Y460089D03*
X646246Y475961D03*
X646794Y472634D03*
X682915Y467823D03*
X708059Y449951D03*
X671145Y454348D03*
X658195Y464248D03*
X653351Y470098D03*
X650837Y472421D03*
X646251Y479161D03*
X675745Y448189D03*
X685815Y496140D03*
X689996Y496274D03*
X694169Y496394D03*
X698475Y496387D03*
X702670Y496148D03*
X707296Y496348D03*
X716700Y445400D03*
X742200Y472500D03*
X724300Y454000D03*
X719100Y478900D03*
X744986Y481255D03*
X749974Y477780D03*
X749628Y471196D03*
X739751Y469686D03*
X735295Y463720D03*
X738636Y457903D03*
X731780Y452531D03*
X729478Y459116D03*
X721600Y451000D03*
X719700Y485600D03*
X735191Y453967D03*
X735231Y457167D03*
X746845Y476389D03*
Y473189D03*
X717993Y451389D03*
X731751Y464398D03*
X735259Y469898D03*
X721445Y455789D03*
X726589Y460909D03*
X743520Y478297D03*
X738745Y472789D03*
X713845Y447289D03*
G54D33*
X71660Y193550D03*
X69100D03*
X66540D03*
Y187050D03*
X71660D03*
G54D51*
X97645Y134201D03*
X92645D03*
X87645D03*
X82645D03*
Y114201D03*
X87645D03*
X92645D03*
X97645D03*
G54D60*
X147553Y327542D03*
X143853Y327642D03*
X136317Y331756D03*
X132717D03*
X124973Y327655D03*
X121255Y327729D03*
X201315Y81433D03*
X154641Y154448D03*
X191557Y344189D03*
X188047Y344249D03*
X180438Y340053D03*
X176898Y340013D03*
X169385Y335813D03*
X165885D03*
X158445Y331748D03*
X154845Y331848D03*
X185315Y410533D03*
X213780Y352494D03*
X210180D03*
X202638Y348349D03*
X199138D03*
X206788Y420845D03*
X207834Y465396D03*
X221100Y134300D03*
X249515Y394680D03*
X224885Y359814D03*
X221424Y359867D03*
X256700Y489500D03*
X260200D03*
X353898Y467743D03*
X349945Y467753D03*
X358012Y467743D03*
X345813D03*
X394125Y398023D03*
X390405D03*
X383048D03*
X379164D03*
X397699D03*
X386726D03*
X375610D03*
X365427Y467743D03*
X361642D03*
X451123Y503983D03*
X504316Y397727D03*
X664700Y543300D03*
G54D24*
X48500Y89400D03*
X48600Y82900D03*
X75969Y219284D03*
X73677Y517540D03*
X62682Y521602D03*
X51402Y517237D03*
X67207Y647187D03*
X67698Y761923D03*
X114371Y182699D03*
X88100Y141100D03*
X118541Y199000D03*
X120741Y194500D03*
X139917Y335856D03*
X128673Y331655D03*
X140363Y517903D03*
X84825Y521698D03*
X95850Y517603D03*
X106904Y521857D03*
X118125Y517858D03*
X129200Y522071D03*
X217622Y101900D03*
X206420Y93789D03*
X205064Y85481D03*
X206690Y102533D03*
X152682Y164664D03*
X163761Y145062D03*
X163249Y176397D03*
X179882Y271928D03*
X179743Y267018D03*
X180756Y261409D03*
X179109Y256562D03*
X178977Y251228D03*
X178850Y246422D03*
X177390Y237502D03*
Y241702D03*
X179810Y281361D03*
X179843Y276656D03*
X180010Y294061D03*
X179910Y285561D03*
X180010Y289861D03*
X162081Y335850D03*
X151010Y331731D03*
X184138Y344153D03*
X173085Y339913D03*
X217480Y356594D03*
X206338Y352449D03*
X195257Y348289D03*
X215500Y449700D03*
X192966Y485443D03*
Y489543D03*
X184504Y517848D03*
X151354Y522037D03*
X162367Y517830D03*
X173487Y522020D03*
X217863Y521903D03*
X206663Y517803D03*
X195563Y522003D03*
X248190Y98033D03*
X227066Y218917D03*
X236158Y405205D03*
X253209Y403106D03*
X228539Y363907D03*
X246103Y428291D03*
X238599Y461252D03*
X238716Y473688D03*
X346234Y792836D03*
X361400Y792962D03*
X462163Y514834D03*
X469795D03*
X490837Y528628D03*
X490883Y537159D03*
X490613Y545645D03*
X490766Y489976D03*
X532700Y393000D03*
X649100Y394600D03*
X673409Y462023D03*
X656909Y478423D03*
X652809Y482723D03*
X669309Y466123D03*
X691700Y544300D03*
X736209Y478623D03*
X740309Y482823D03*
X723809Y466123D03*
X719709Y462023D03*
X750700Y546500D03*
X752900Y555900D03*
Y551800D03*
X753000Y577500D03*
X752930Y569233D03*
X752937Y560714D03*
X753029Y573387D03*
X729200Y853200D03*
G54D15*
X6614Y553544D03*
X10551Y623622D03*
X6614Y671654D03*
X10551Y741732D03*
X18425Y553544D03*
X32204D03*
X18425Y623622D03*
X32204D03*
X18425Y671654D03*
X32204D03*
X18425Y741732D03*
X32204D03*
G54D42*
X30494Y493063D03*
X83288Y184954D03*
X162913Y171759D03*
X155231Y176850D03*
X213782Y427789D03*
X216943Y418666D03*
X250300Y461100D03*
X241356Y478217D03*
X242273Y468923D03*
X304774Y475788D03*
X300300Y462500D03*
X304813Y471007D03*
G54D52*
X151866Y100449D03*
X189416D03*
G54D70*
X217108Y145568D03*
Y163568D03*
G54D43*
X75118Y561024D03*
Y564174D03*
Y567323D03*
Y570473D03*
Y573622D03*
Y576772D03*
Y579922D03*
Y583071D03*
Y586221D03*
Y589370D03*
Y592520D03*
Y595670D03*
Y598819D03*
Y601969D03*
Y605118D03*
Y608268D03*
Y611418D03*
Y614567D03*
Y679134D03*
Y682284D03*
Y685433D03*
Y688583D03*
Y691732D03*
Y694882D03*
Y698032D03*
Y701181D03*
Y704331D03*
Y707480D03*
Y710630D03*
Y713780D03*
Y716929D03*
Y720079D03*
Y723228D03*
Y726378D03*
Y729528D03*
Y732677D03*
X85000Y562599D03*
Y565748D03*
Y568898D03*
Y572048D03*
Y575197D03*
Y578347D03*
Y581496D03*
Y584646D03*
Y587796D03*
Y590945D03*
Y594095D03*
Y597244D03*
Y600394D03*
Y603544D03*
Y606693D03*
Y609843D03*
Y612992D03*
Y616142D03*
Y680709D03*
Y683858D03*
Y687008D03*
Y690158D03*
Y693307D03*
Y696457D03*
Y699606D03*
Y702756D03*
Y705906D03*
Y709055D03*
Y712205D03*
Y715354D03*
Y718504D03*
Y721654D03*
Y724803D03*
Y727953D03*
Y731102D03*
Y734252D03*
X175118Y818504D03*
Y821654D03*
Y824804D03*
Y827954D03*
Y831104D03*
Y834254D03*
Y837399D03*
X165238Y816929D03*
Y820079D03*
Y823229D03*
Y826379D03*
Y829529D03*
Y832679D03*
Y835829D03*
X175118Y840549D03*
X165238Y838974D03*
Y842124D03*
X175118Y843699D03*
Y846849D03*
Y849999D03*
Y853149D03*
Y856299D03*
X165238Y845274D03*
Y848424D03*
Y851574D03*
Y854724D03*
G54D61*
X147553Y323942D03*
X143853Y324042D03*
X136317Y328156D03*
X132717D03*
X124973Y324055D03*
X121255Y324129D03*
X201315Y77833D03*
X154641Y150848D03*
X202638Y344749D03*
X199138D03*
X191557Y340589D03*
X188047Y340649D03*
X180438Y336453D03*
X176898Y336413D03*
X169385Y332213D03*
X165885D03*
X158445Y328148D03*
X154845Y328248D03*
X185315Y406933D03*
X213780Y348894D03*
X210180D03*
X206788Y417245D03*
X207834Y461796D03*
X221100Y130700D03*
X249515Y391080D03*
X224885Y356214D03*
X221424Y356267D03*
X256700Y485900D03*
X260200D03*
X353898Y464143D03*
X349945Y464153D03*
X358012Y464143D03*
X345813D03*
X394125Y394423D03*
X390405D03*
X383048D03*
X379164D03*
X397699D03*
X386726D03*
X375610D03*
X365427Y464143D03*
X361642D03*
X451123Y500383D03*
X504316Y394127D03*
X664700Y539700D03*
G54D25*
X63000Y103300D03*
X67300D03*
X50963Y382383D03*
X46763Y397883D03*
X50830Y397889D03*
X50963Y390183D03*
X46763Y390483D03*
X61563Y374283D03*
X60122Y754461D03*
X107783Y86561D03*
X91178Y211333D03*
X80326Y658988D03*
X79967Y643494D03*
X80653Y758647D03*
X80415Y776333D03*
X208612Y81430D03*
X219504Y181570D03*
X177087Y175433D03*
X185215Y418033D03*
X185266Y493043D03*
X219303Y748114D03*
X229613Y64898D03*
X223817Y181608D03*
X235414Y217713D03*
X240662Y387084D03*
X241728Y360156D03*
X237455Y371255D03*
X238000Y418100D03*
X227900Y418000D03*
X242700Y440000D03*
X232100Y418000D03*
X223658Y748114D03*
X234524Y774783D03*
X447090Y503842D03*
X504027Y412875D03*
X504094Y405332D03*
X503981Y420419D03*
X525463Y545933D03*
X665909Y466123D03*
X649409Y482723D03*
X670009Y462023D03*
X653509Y478423D03*
X711409Y453923D03*
X650700Y532900D03*
X689190Y771506D03*
X715509Y457923D03*
X732109Y474523D03*
X727909Y470223D03*
G54D16*
X22980Y59055D03*
X30854D03*
X22980Y106299D03*
Y98425D03*
Y90551D03*
Y82677D03*
Y74803D03*
Y66929D03*
X30854Y106299D03*
Y98425D03*
Y90551D03*
Y82677D03*
Y74803D03*
Y66929D03*
X41142Y135669D03*
Y155669D03*
Y145669D03*
X26181Y537559D03*
Y527559D03*
Y517559D03*
X41142Y655669D03*
Y645669D03*
Y635669D03*
Y763780D03*
Y753780D03*
Y773780D03*
G54D34*
X72915Y261033D03*
X52081Y407029D03*
X43512Y406131D03*
X40615Y397833D03*
X71815Y373833D03*
X44515Y482933D03*
X52315Y497433D03*
X51015Y491933D03*
X49815Y502633D03*
X43515Y490933D03*
X142615Y167533D03*
X119300Y181500D03*
X219115Y62233D03*
X155600Y139000D03*
X200015Y250333D03*
X192615Y254537D03*
X188615Y262433D03*
X196015Y265433D03*
X196215Y274233D03*
X187601Y275296D03*
X193115Y282033D03*
X186663Y450083D03*
X186363Y444183D03*
X186016Y432468D03*
X192815Y433733D03*
X198615Y449033D03*
X193915Y441633D03*
X186163Y438083D03*
X235215Y182933D03*
X235715Y755233D03*
X325013Y789701D03*
X333871Y786092D03*
X451015Y514433D03*
X680100Y541000D03*
X689500Y532100D03*
G54D17*
X29528Y19685D03*
X76772D03*
X108268Y905512D03*
X155512D03*
G54D62*
X109410Y796831D03*
Y876397D03*
X168465Y796831D03*
Y876397D03*
G54D71*
X228358Y154568D03*
G54D80*
X234222Y399876D03*
Y396136D03*
Y392396D03*
X243222D03*
Y399876D03*
G54D26*
X63000Y99900D03*
X67300D03*
X50963Y378983D03*
X46763Y394483D03*
X50830Y394489D03*
X50963Y386783D03*
X46763Y387083D03*
X61563Y370883D03*
X60122Y751061D03*
X107783Y83161D03*
X91178Y207933D03*
X80326Y655588D03*
X79967Y640094D03*
X80653Y755247D03*
X80415Y772933D03*
X208612Y78030D03*
X219504Y178170D03*
X177087Y172033D03*
X185215Y414633D03*
X185266Y489643D03*
X219303Y744714D03*
X229613Y61498D03*
X223817Y178208D03*
X235414Y214313D03*
X238000Y414700D03*
X227900Y414600D03*
X232100D03*
X240662Y383684D03*
X241728Y356756D03*
X237455Y367855D03*
X242700Y436600D03*
X223658Y744714D03*
X234524Y771383D03*
X447090Y500442D03*
X504027Y409475D03*
X504094Y401932D03*
X503981Y417019D03*
X525463Y542533D03*
X665909Y462723D03*
X649409Y479323D03*
X670009Y458623D03*
X653509Y475023D03*
X711409Y450523D03*
X650700Y529500D03*
X689190Y768106D03*
X715509Y454523D03*
X732109Y471123D03*
X727909Y466823D03*
G54D44*
X68140Y665912D03*
X104541Y207700D03*
X250667Y69296D03*
X277770Y794774D03*
X532500Y397400D03*
G54D35*
X53547Y322486D03*
Y302486D03*
X182681Y580832D03*
Y560832D03*
G54D53*
X139878Y135201D03*
Y150469D03*
G54D27*
X70675Y134665D03*
X54925D03*
X70675Y155935D03*
X54925D03*
G54D54*
X115608Y122826D03*
Y114926D03*
X105808Y122826D03*
Y114926D03*
G54D72*
X204150Y173700D03*
X196250D03*
X236750Y135300D03*
X244650D03*
X643373Y530113D03*
X635473D03*
X702250Y533300D03*
X710150D03*
G54D81*
X268768Y415628D03*
Y430628D03*
G54D90*
X702989Y515755D03*
X691989D03*
X703000Y524500D03*
X692000D03*
G54D63*
X216447Y72290D03*
Y74259D03*
Y76227D03*
Y78196D03*
Y80164D03*
Y82133D03*
Y84102D03*
Y86070D03*
Y88039D03*
Y90007D03*
Y91976D03*
X235733D03*
Y90007D03*
Y88039D03*
Y86070D03*
Y84102D03*
Y82133D03*
Y80164D03*
Y78196D03*
Y76227D03*
Y74259D03*
Y72290D03*
G54D18*
X58059Y84803D03*
Y86768D03*
Y88738D03*
Y90708D03*
Y92673D03*
X74359D03*
Y90708D03*
Y88738D03*
Y86768D03*
Y84803D03*
X107899Y197156D03*
Y195191D03*
Y193221D03*
Y191251D03*
Y189286D03*
X91599D03*
Y191251D03*
Y193221D03*
Y195191D03*
Y197156D03*
X82163Y244428D03*
Y246398D03*
Y248368D03*
Y250338D03*
Y252308D03*
Y254278D03*
Y256248D03*
Y258218D03*
Y260188D03*
Y262158D03*
Y264128D03*
Y266098D03*
Y268068D03*
Y270038D03*
Y272008D03*
Y273978D03*
Y275948D03*
Y277918D03*
Y279888D03*
Y281858D03*
Y283828D03*
Y285798D03*
Y287768D03*
Y289738D03*
X157763Y273978D03*
Y272008D03*
Y270038D03*
Y268068D03*
Y266098D03*
Y264128D03*
Y262158D03*
Y260188D03*
Y258218D03*
Y256248D03*
Y254278D03*
Y252308D03*
Y250338D03*
Y248368D03*
Y246398D03*
Y244428D03*
Y289738D03*
Y287768D03*
Y285798D03*
Y283828D03*
Y281858D03*
Y279888D03*
Y277918D03*
Y275948D03*
X476320Y508067D03*
Y506102D03*
Y504132D03*
Y502162D03*
Y500197D03*
X460020D03*
Y502162D03*
Y504132D03*
Y506102D03*
Y508067D03*
G54D45*
X62540Y665912D03*
X98941Y207700D03*
X245067Y69296D03*
X272170Y794774D03*
X526900Y397400D03*
G54D36*
G01X63351Y294778D02*
Y290678D01*
G01D02*
X61346D01*
X59807Y289139D01*
X59096D01*
G01X68901Y400320D02*
X66931Y398350D01*
G01X61563Y370833D02*
Y367333D01*
X61702Y367194D01*
X61776D01*
G01X74863Y390483D02*
X76775Y392395D01*
Y392446D01*
G01X50963Y386733D02*
X47063D01*
X46763Y387033D01*
G01D02*
X43697D01*
X43521Y386857D01*
X43345D01*
G01X70865Y390502D02*
X72809Y392446D01*
X72838D01*
G01X70952Y414050D02*
X71039Y414137D01*
Y414269D01*
X72838Y416068D01*
G01X70845Y405839D02*
Y406201D01*
X72838Y408194D01*
G01X70775Y398396D02*
X70914D01*
X72838Y400320D01*
G01X46863Y378933D02*
X46397Y379399D01*
X43654D01*
X43569Y379314D01*
G01X50830Y397939D02*
X51385D01*
X52891Y396433D01*
X54515D01*
G01X46763Y397933D02*
X50824D01*
X50830Y397939D01*
G01X66931Y484968D02*
X68898Y486935D01*
X68901D01*
G01X66963Y473083D02*
X67005D01*
X68901Y471187D01*
G01Y482998D02*
X66931Y484968D01*
G01X79081Y465348D02*
Y465136D01*
X80712Y463505D01*
Y463313D01*
G01X70704Y429620D02*
Y429669D01*
X68901Y431472D01*
Y431816D01*
G01X67015Y449433D02*
X68883Y447565D01*
X68901D01*
G01X74639Y441855D02*
Y441826D01*
X76775Y439690D01*
G01X78754Y453353D02*
X80559Y451548D01*
X80666D01*
X80712Y451502D01*
G01X78811Y426113D02*
Y425978D01*
X76775Y423942D01*
G01X66903Y457689D02*
X66957Y457635D01*
Y457383D01*
X68901Y455439D01*
G01X76775Y479061D02*
X74805Y481031D01*
G01X70759Y449277D02*
X71126D01*
X72838Y447565D01*
G01X70869Y421840D02*
Y421973D01*
X72838Y423942D01*
G01X74801Y433368D02*
X74390D01*
X72838Y431816D01*
G01X79094Y441620D02*
Y441308D01*
X80712Y439690D01*
G01X74451Y465323D02*
X74521Y465253D01*
X74835D01*
X76775Y463313D01*
G01X66991Y476766D02*
X67259D01*
X68901Y475124D01*
G01X79050Y457367D02*
Y457101D01*
X80712Y455439D01*
G01X74805Y481031D02*
X76772Y482998D01*
X76775D01*
G01X78742Y488905D02*
X76775Y486938D01*
Y486935D01*
G01X80712D02*
X78742Y488905D01*
G01X76775Y490872D02*
X74805Y492842D01*
G01X66961Y488885D02*
X68901Y490825D01*
Y490872D01*
G01X74805Y492842D02*
X76772Y494809D01*
X76775D01*
G01X122100Y203300D02*
Y203100D01*
X121800Y202800D01*
X118591D01*
G01X118621Y206661D02*
X121361D01*
X122000Y207300D01*
G01X145771Y414191D02*
X145863Y414283D01*
Y414289D01*
X147642Y416068D01*
G01X82555Y406288D02*
X82463Y406380D01*
Y406443D01*
X80712Y408194D01*
G01X110472Y394496D02*
X112208Y396232D01*
Y396383D01*
G01X108271D02*
X110158Y394496D01*
X110472D01*
G01X145765Y406438D02*
X145886D01*
X147642Y408194D01*
G01X120083D02*
X122053Y406224D01*
G01X112208Y408194D02*
X114175Y410161D01*
G01X116145Y412131D02*
X114175Y410161D01*
G01X124020Y408194D02*
Y408191D01*
X122053Y406224D01*
G01X125990Y394413D02*
X127957Y396380D01*
Y396383D01*
G01X124020D02*
X125990Y394413D01*
G01X141738D02*
X143705Y396380D01*
Y396383D01*
G01X139768D02*
X141738Y394413D01*
G01X100397Y416068D02*
X98427Y414098D01*
G01X108271Y416068D02*
X108268D01*
X106301Y418035D01*
G01X112208Y416068D02*
X114175Y418035D01*
G01X124020Y416068D02*
X125990Y414098D01*
G01X92523Y412131D02*
X90553Y410161D01*
G01X88586Y408194D02*
X90553Y410161D01*
G01X104334Y412131D02*
X104215D01*
X102263Y414083D01*
G01X104334Y416068D02*
X104248D01*
X102263Y414083D01*
G01X104334Y408194D02*
X102364Y406224D01*
G01X131894Y412131D02*
X133864Y410161D01*
G01X135831Y408194D02*
X133864Y410161D01*
G01X131894Y408194D02*
X131897D01*
X133864Y410161D01*
G01X100397Y408194D02*
Y408191D01*
X102364Y406224D01*
G01X135831Y416068D02*
X135678D01*
X133863Y417883D01*
G01X127957Y416068D02*
Y416065D01*
X125990Y414098D01*
G01X96460Y416068D02*
Y416065D01*
X98427Y414098D01*
G01X94367Y394479D02*
X96271Y396383D01*
X96460D01*
G01X92523D02*
Y396323D01*
X94367Y394479D01*
G01X112208Y412131D02*
X110238Y410161D01*
G01X139768Y416068D02*
X141738Y414098D01*
G01X116145Y416068D02*
X114175Y414098D01*
G01X120083Y416068D02*
X122053Y414098D01*
G01X124020Y412131D02*
X125990Y410161D01*
G01X100397Y412131D02*
X98427Y410161D01*
G01X86663Y402383D02*
X86563D01*
G01X84649Y404257D02*
X84789D01*
X86663Y402383D01*
G01X88586Y396383D02*
X86616Y394413D01*
G01X84649Y400320D02*
X86712Y402383D01*
X86663D01*
G01X88586Y412131D02*
X90553Y414098D01*
G01X84649Y392446D02*
X86163Y390932D01*
Y390783D01*
X86463Y390483D01*
G01X100397Y396383D02*
X100584D01*
X102555Y394412D01*
G01X131894Y396383D02*
X133722Y394555D01*
X133964D01*
G01X116145Y396383D02*
Y396526D01*
X118130Y398511D01*
G01X92523Y408194D02*
X94393Y406324D01*
X94579D01*
G01X131894Y416068D02*
X133863Y414099D01*
Y413773D01*
G01X151579Y396383D02*
X149598Y394402D01*
X149431D01*
G01X143705Y412131D02*
X143837D01*
X145795Y410173D01*
G01D02*
X143816Y408194D01*
X143705D01*
G01X145795Y410173D02*
X147642Y412020D01*
Y412131D01*
G01X86463Y390483D02*
Y390383D01*
X86163Y390083D01*
Y390023D01*
X84649Y388509D01*
G01X86616Y394413D02*
X86519Y394510D01*
Y394513D01*
X84649Y396383D01*
G01X102555Y394412D02*
X104334Y396191D01*
Y396383D01*
G01X133964Y394555D02*
X135789Y396380D01*
X135828D01*
X135831Y396383D01*
G01X90553Y414098D02*
X92523Y416068D01*
G01X98427Y410161D02*
X96460Y412128D01*
Y412131D01*
G01X118130Y398511D02*
X120083Y396558D01*
Y396383D01*
G01X94579Y406324D02*
X94590D01*
X96460Y408194D01*
G01X125990Y410161D02*
X127957Y412128D01*
Y412131D01*
G01X122053Y414098D02*
X122050D01*
X120083Y412131D01*
G01X133863Y413773D02*
X134189D01*
X135831Y412131D01*
G01X110238Y410161D02*
X108271Y412128D01*
Y412131D01*
G01X149431Y394402D02*
Y394594D01*
X147642Y396383D01*
G01X116145Y408194D02*
X114175Y406224D01*
G01X126063Y406183D02*
Y406300D01*
X127957Y408194D01*
G01X139768D02*
X141738Y406224D01*
G01X108271Y408194D02*
X106301Y406224D01*
G01X137801Y453472D02*
X139768Y451505D01*
Y451502D01*
G01X135831D02*
X137801Y453472D01*
G01Y445598D02*
X139768Y443631D01*
Y443628D01*
G01X135831D02*
X137801Y445598D01*
G01X133864Y437720D02*
X135831Y439687D01*
Y439690D01*
G01X131894Y443628D02*
X133864Y445598D01*
G01X133953Y425813D02*
X135824Y423942D01*
X135831D01*
G01X131894Y435753D02*
X133864Y433783D01*
G01D02*
X135831Y431816D01*
G01X110332Y425814D02*
X108271Y427875D01*
Y427879D01*
G01X106210Y421976D02*
X104334Y423852D01*
Y423942D01*
G01X94263Y418129D02*
Y418265D01*
X92523Y420005D01*
G01X96460Y423942D02*
Y423786D01*
X98363Y421883D01*
G01X102364Y429846D02*
X100397Y431813D01*
Y431816D01*
G01X133864Y433783D02*
X135831Y435750D01*
Y435753D01*
G01X104334Y439690D02*
X106263Y437761D01*
Y437583D01*
G01X100397Y447565D02*
X100790D01*
X102684Y445671D01*
G01X98363Y421883D02*
X100397Y423917D01*
Y423942D01*
G01X106263Y437583D02*
X104433Y435753D01*
X104334D01*
G01X102684Y445671D02*
X104334Y444021D01*
Y443628D01*
G01X147642D02*
X149612Y445598D01*
G01X147642Y435753D02*
X149612Y433783D01*
G01X86493Y441401D02*
Y441713D01*
X88408Y443628D01*
X88586D01*
G01Y435753D02*
X86616Y433783D01*
G01X86687Y421669D02*
Y421873D01*
X84649Y423911D01*
Y423942D01*
G01X135831Y475124D02*
X137801Y477094D01*
G01X147642Y475124D02*
X149612Y477094D01*
G01X98626Y477049D02*
X98385D01*
X96460Y475124D01*
G01X116145D02*
X114175Y477094D01*
G01X104334Y475124D02*
X102364Y477094D01*
G01X118163Y429883D02*
X116230Y431816D01*
X116145D01*
G01X120083Y423942D02*
X122053Y421972D01*
G01X120083Y420005D02*
X122053Y418035D01*
G01X108271Y420005D02*
X106301Y418035D01*
G01X104334Y420005D02*
Y420002D01*
X106301Y418035D01*
G01X116145Y420005D02*
X114175Y418035D01*
G01X131894Y420005D02*
Y419852D01*
X133863Y417883D01*
G01X120083Y423942D02*
Y423974D01*
G01X124020Y423942D02*
X123835D01*
G01X124020Y420005D02*
Y420002D01*
X122053Y418035D01*
G01X127957Y423942D02*
X128111D01*
X130081Y425912D01*
G01X124020Y423942D02*
Y423939D01*
X122053Y421972D01*
G01X116145Y423942D02*
X116111D01*
X114091Y425962D01*
G01X112208Y423942D02*
Y424079D01*
X114091Y425962D01*
G01X131894Y427879D02*
Y427725D01*
X130081Y425912D01*
G01X127957Y427879D02*
X128114D01*
X130081Y425912D01*
G01X124020Y427879D02*
X123988D01*
X121943Y425834D01*
G01X120083Y427879D02*
Y427694D01*
X121943Y425834D01*
G01X116145Y427879D02*
X116008D01*
X114091Y425962D01*
G01X112208Y427879D02*
Y427845D01*
X114091Y425962D01*
G01X112208Y447565D02*
X114175Y445598D01*
G01X125990D02*
X124020Y443628D01*
G01X110238Y437720D02*
X108271Y435753D01*
G01X112208Y439690D02*
X110238Y437720D01*
G01X124020Y435753D02*
X124023D01*
X125990Y437720D01*
G01X116145Y435753D02*
Y435786D01*
X117951Y437592D01*
G01X127957Y439690D02*
Y439687D01*
X125990Y437720D01*
G01X120083Y439690D02*
X120049D01*
X117951Y437592D01*
G01X116145Y443628D02*
Y443667D01*
X118189Y445711D01*
G01X120083Y447565D02*
X120043D01*
X118189Y445711D01*
G01X108271Y443628D02*
X108318D01*
G01X106341Y426062D02*
X104524Y427879D01*
X104334D01*
G01X110238Y453472D02*
X108271Y451505D01*
Y451502D01*
G01X112208D02*
X110238Y453472D01*
G01X120083Y431816D02*
X122053Y429846D01*
G01X127957Y431816D02*
X124020D01*
G01X116145Y451502D02*
X116323D01*
X118238Y453417D01*
G01X125897Y453240D02*
X126174D01*
X127912Y451502D01*
X127957D01*
G01X114063Y429879D02*
X112208Y431734D01*
Y431816D01*
G01X118238Y453417D02*
Y453402D01*
X120083Y451557D01*
Y451502D01*
G01X122053Y429846D02*
X124020Y431813D01*
Y431816D01*
G01X96460Y459376D02*
X96512D01*
X98597Y457291D01*
G01D02*
Y457239D01*
X100397Y455439D01*
G01X98597Y457291D02*
X96745Y455439D01*
X96460D01*
G01X130080Y457372D02*
X131894Y455558D01*
Y455439D01*
G01X141827Y461346D02*
Y461254D01*
X143705Y459376D01*
G01Y427879D02*
X145675Y425909D01*
G01X143705Y471187D02*
X145675Y473157D01*
G01X143705Y463313D02*
X145675Y465283D01*
G01D02*
X147642Y467250D01*
G01X139768Y486935D02*
X141738Y488905D01*
G01X127957Y463313D02*
X129927Y465283D01*
G01X135831Y459376D02*
X137801Y461346D01*
G01X135831Y455439D02*
X137801Y457409D01*
G01X112208Y486935D02*
X110238Y488905D01*
G01X116145Y471187D02*
X114175Y473157D01*
G01X120083Y467250D02*
X122053Y469220D01*
G01X124020Y486935D02*
X125990Y488905D01*
G01X94377Y489018D02*
X96460Y486935D01*
G01X84649Y475124D02*
X82679Y477094D01*
G01X139768Y435753D02*
X137801Y437720D01*
G01X127957Y443628D02*
X129927Y445598D01*
G01X139768Y463313D02*
X137801Y461346D01*
G01X131894Y451502D02*
Y447565D01*
G01X92523Y486935D02*
Y486938D01*
X94377Y488792D01*
Y489018D01*
G01X116145Y439690D02*
X114175Y437720D01*
G01X112208Y443628D02*
X110238Y445598D01*
G01X135831Y427879D02*
X133864Y429846D01*
G01X135831Y420005D02*
X133864Y421972D01*
G01X139768Y447565D02*
X141738Y449535D01*
G01X124020Y447565D02*
X122053Y445598D01*
G01X127957Y471187D02*
X129927Y473157D01*
G01X104334Y447565D02*
Y451502D01*
G01X131894Y439690D02*
Y439687D01*
X129927Y437720D01*
G01X88586Y423942D02*
X90363Y422165D01*
Y421975D01*
X90408Y421930D01*
G01X90544Y433408D02*
Y433774D01*
X92523Y435753D01*
G01X104334Y431816D02*
X104396D01*
X106263Y433683D01*
G01X94661Y441681D02*
Y441685D01*
X92718Y443628D01*
X92523D01*
G01X124020Y439690D02*
Y439687D01*
X122053Y437720D01*
G01X108271Y423942D02*
X108306D01*
X110065Y422183D01*
X110219D01*
X110289Y422113D01*
G01X106363Y441583D02*
X108256Y439690D01*
X108271D01*
G01X118134Y449362D02*
X117942D01*
X116145Y447565D01*
G01X96460Y420005D02*
Y420002D01*
X98282Y418180D01*
X98533D01*
G01X137767Y425993D02*
X139653Y427879D01*
X139768D01*
G01X126180Y418224D02*
Y418228D01*
X127957Y420005D01*
G01X104334Y467250D02*
X106427Y465157D01*
X106449D01*
G01X104334Y451502D02*
Y451554D01*
X106263Y453483D01*
G01X92523Y463313D02*
X91940Y462730D01*
X91788D01*
X90662Y461604D01*
G01X88586Y471187D02*
X90350Y472951D01*
Y473069D01*
G01X120083Y475124D02*
X120086D01*
X122053Y473157D01*
G01X108271Y471187D02*
Y471075D01*
X110263Y469083D01*
G01X135831Y463313D02*
X135834D01*
X137801Y461346D01*
G01D02*
X139768Y459379D01*
Y459376D01*
G01X149719Y457328D02*
X151579Y455468D01*
Y455439D01*
G01X145675Y465283D02*
X147642Y463316D01*
Y463313D01*
G01X129927Y437720D02*
X127960Y435753D01*
X127957D01*
G01X90408Y421930D02*
X90363Y421885D01*
Y421782D01*
X88586Y420005D01*
G01X106263Y433683D02*
X108130Y431816D01*
X108271D01*
G01X114175Y437720D02*
X112208Y435753D01*
G01X122053Y437720D02*
X120086Y435753D01*
X120083D01*
G01X110289Y422113D02*
X110363Y422039D01*
Y421885D01*
X112208Y420040D01*
Y420005D01*
G01X110238Y445598D02*
X108271Y447565D01*
G01X98533Y418180D02*
X98572D01*
X100397Y420005D01*
G01X133864Y429846D02*
X131894Y431816D01*
G01X133864Y421972D02*
X131894Y423942D01*
G01X141738Y449535D02*
X143705Y451502D01*
G01X129927Y445598D02*
X131894Y447565D01*
G01X122053Y445598D02*
X120083Y443628D01*
G01X106449Y465157D02*
X106623Y464983D01*
Y464961D01*
X108271Y463313D01*
G01X106263Y453483D02*
X104334Y455412D01*
Y455439D01*
G01X90662Y461604D02*
X92523Y459743D01*
Y459376D01*
G01X82679Y477094D02*
X80712Y475127D01*
Y475124D01*
G01X90350Y473069D02*
X90641D01*
X92523Y471187D01*
G01X125990Y488905D02*
X127957Y486938D01*
Y486935D01*
G01X122053Y473157D02*
X124020Y471190D01*
Y471187D01*
G01X110263Y469083D02*
X112096Y467250D01*
X112208D01*
G01X122053Y469220D02*
X120086Y471187D01*
X120083D01*
G01X110238Y488905D02*
X108271Y486938D01*
Y486935D01*
G01X137801Y457409D02*
X139768Y455442D01*
Y455439D01*
G01X129927Y473157D02*
X131894Y475124D01*
G01X141738Y488905D02*
X143705Y486938D01*
Y486935D01*
G01X118004Y488825D02*
X118193D01*
X120083Y486935D01*
G01X116145D02*
Y486966D01*
X118004Y488825D01*
G01X133864Y488905D02*
X135831Y486938D01*
Y486935D01*
G01X131894D02*
X133864Y488905D01*
G01X147642Y486935D02*
X149612Y488905D01*
G01X102308Y488978D02*
X104334Y486952D01*
Y486935D01*
G01X100397D02*
Y487067D01*
X102308Y488978D01*
G01X86616Y488905D02*
X84649Y486938D01*
Y486935D01*
G01X88586D02*
X86616Y488905D01*
G01X143705Y467250D02*
X145675Y469220D01*
G01X147642Y471187D02*
X145675Y469220D01*
G01X112208Y475124D02*
X110238Y477094D01*
G01X108271Y475124D02*
Y475127D01*
X110238Y477094D01*
G01X139768Y475124D02*
X141738Y477094D01*
G01X135831Y471187D02*
X137801Y473157D01*
G01X108271Y467250D02*
X106301Y469220D01*
G01X104334Y471187D02*
X106301Y469220D01*
G01X116145Y467250D02*
X114175Y469220D01*
G01X112208Y471187D02*
X114175Y469220D01*
G01X127957Y467250D02*
X129927Y469220D01*
G01X131894Y471187D02*
X129927Y469220D01*
G01X135831Y467250D02*
X137801Y469220D01*
G01X120083Y463313D02*
X122053Y465283D01*
G01X131894Y463313D02*
X133864Y465283D01*
G01X131894Y467250D02*
X131897D01*
X133864Y465283D01*
G01X104334Y463313D02*
X100397D01*
G01X106301Y461346D02*
X104334Y463313D01*
G01Y459376D02*
Y459379D01*
X106301Y461346D01*
G01X131894Y459376D02*
X129987Y461283D01*
X129963D01*
G01X108271Y455439D02*
X108419D01*
X110263Y457283D01*
G01X112208Y455439D02*
X112107D01*
X110263Y457283D01*
G01X108271Y459376D02*
Y459275D01*
X110263Y457283D01*
G01X120083Y455439D02*
X120107D01*
X122158Y453388D01*
G01X124020Y475124D02*
X125990Y477094D01*
G01X88586Y475124D02*
X90376Y476914D01*
Y476918D01*
G01X124020Y467250D02*
X126057Y469287D01*
G01X112208Y463313D02*
X108271Y467250D01*
G01X124020Y451502D02*
Y451526D01*
X122158Y453388D01*
G01X127957Y459376D02*
X128056D01*
X129963Y461283D01*
G01X112208Y459376D02*
Y459228D01*
X110263Y457283D01*
G01X124020Y463313D02*
Y463316D01*
X122053Y465283D01*
G01X139768Y467250D02*
Y467253D01*
X137801Y469220D01*
G01X139768Y471187D02*
Y471190D01*
X137801Y473157D01*
G01X143705Y475124D02*
Y475127D01*
X141738Y477094D01*
G01X127957Y475124D02*
Y475127D01*
X125990Y477094D01*
G01X100397Y475124D02*
X100447D01*
X102227Y473344D01*
G01X92523Y475124D02*
X90729Y476918D01*
X90376D01*
G01X135831Y447565D02*
X137801Y449535D01*
G01X94377Y489070D02*
Y489018D01*
G01X149612Y488905D02*
X151579Y486938D01*
Y486935D01*
G01X166649Y131897D02*
X166700Y131846D01*
Y128800D01*
G01X179932Y271928D02*
X180071Y271847D01*
X182960D01*
X183082Y271969D01*
G01X179893Y276656D02*
X182718D01*
X182720Y276658D01*
X183043D01*
G01X179960Y285561D02*
X180013Y286883D01*
X180060Y289861D01*
G01Y294061D02*
Y289861D01*
G01X179860Y281361D02*
X181852D01*
X183653Y283162D01*
G01X169290Y417960D02*
X167398Y416068D01*
X167327D01*
G01X175463Y413760D02*
X173834Y412131D01*
X171264D01*
G01X161499Y402554D02*
X161490Y402563D01*
X161147D01*
X159453Y404257D01*
G01X169297Y402536D02*
X169048D01*
X167327Y404257D01*
G01X157502Y390427D02*
X155516Y392413D01*
Y392446D01*
G01X151579Y404257D02*
X151963Y403873D01*
Y400704D01*
X151579Y400320D01*
G01D02*
X151983Y399916D01*
Y396787D01*
X151579Y396383D01*
G01Y392446D02*
X149783Y390650D01*
Y390487D01*
G01X169503Y386977D02*
X168859D01*
X167327Y388509D01*
G01X159453Y392446D02*
Y392311D01*
X161213Y390551D01*
G01X174124Y402624D02*
X174122D01*
X172489Y404257D01*
X171264D01*
G01X173155Y417978D02*
Y417959D01*
X171264Y416068D01*
G01X161277Y414114D02*
Y414167D01*
X159453Y415991D01*
Y416068D01*
G01X161241Y398226D02*
Y398369D01*
X159453Y400157D01*
Y400320D01*
G01X157574Y394185D02*
X155516Y396243D01*
Y396383D01*
G01X149783Y390487D02*
X149791D01*
X151579Y388699D01*
Y388509D01*
G01X161213Y390551D02*
X160981Y390319D01*
Y390037D01*
X159453Y388509D01*
G01X190765Y476128D02*
X190666Y476029D01*
X185934D01*
G01X159453Y467250D02*
X161423Y469220D01*
G01X153583Y461058D02*
X153261D01*
X151579Y459376D01*
G01X167327Y475124D02*
X169297Y477094D01*
G01X167327Y463313D02*
X169297Y465283D01*
G01X155516Y439690D02*
X157486Y437720D01*
G01Y429846D02*
X159453Y431813D01*
Y431816D01*
G01X155516D02*
X157486Y429846D01*
G01X159453Y427879D02*
X157486Y429846D01*
G01X153416Y445539D02*
X153419D01*
X155445Y447565D01*
X155516D01*
G01X167327Y439690D02*
X169297Y437720D01*
G01X169112Y453260D02*
X169085D01*
X167327Y451502D01*
G01X169166Y429679D02*
X168736Y429249D01*
X168697D01*
X167327Y427879D01*
G01X185934Y470029D02*
X190666D01*
X190765Y470128D01*
G01X155516Y486935D02*
X157486Y488905D01*
G01X163390Y486935D02*
X161423Y484968D01*
G01X159453Y479061D02*
X161423Y481031D01*
G01X155516Y471187D02*
X157486Y473157D01*
G01X163390Y467250D02*
X165360Y469220D01*
G01X151579Y475124D02*
X153549Y477094D01*
G01X171264Y463313D02*
X173234Y465283D01*
G01X171264Y451502D02*
X173234Y453472D01*
G01X159453Y439690D02*
X161423Y437720D01*
G01X151579Y435753D02*
X153549Y433783D01*
G01X173234Y437720D02*
X171264Y439690D01*
G01X153422Y441722D02*
X153363Y441781D01*
Y441844D01*
X151579Y443628D01*
G01X161363Y425780D02*
X161360D01*
X161263Y425683D01*
X161197D01*
X159456Y423942D01*
X159453D01*
G01X174351Y429014D02*
X173216Y427879D01*
X171264D01*
G01X175150Y476294D02*
X172434D01*
X171264Y475124D01*
G01X174086Y484839D02*
X172534Y483287D01*
X171553D01*
X171264Y482998D01*
G01X193016Y481243D02*
X195038Y479221D01*
Y477148D01*
G01X207834Y461846D02*
X211084D01*
X211243Y462005D01*
G01X203406Y454885D02*
X198910D01*
X197214Y456581D01*
G01X203439Y459152D02*
Y454918D01*
X203406Y454885D01*
G01X161423Y481031D02*
X159456Y482998D01*
X159453D01*
G01X161423Y484968D02*
X163390Y483001D01*
Y482998D01*
G01X165360Y488905D02*
X167327Y486938D01*
Y486935D01*
G01X157486Y488905D02*
X159453Y486938D01*
Y486935D01*
G01X155516Y475124D02*
X153549Y473157D01*
G01X151579Y471187D02*
X153549Y473157D01*
G01X167327Y490872D02*
X165360Y488905D01*
G01X159453Y490872D02*
X161423Y492842D01*
G01X193016Y493343D02*
Y496643D01*
G01X169297Y492842D02*
X168856Y493283D01*
X168853D01*
X167327Y494809D01*
G01X216300Y499600D02*
Y493942D01*
X216324Y493918D01*
G01X161423Y492842D02*
X159456Y494809D01*
X159453D01*
G01X231216Y783159D02*
Y787290D01*
X231171Y787335D01*
G01D02*
Y792577D01*
X230515Y793233D01*
G01X234524Y774833D02*
X237804D01*
X237950Y774979D01*
G01X234612Y779010D02*
X237760D01*
X237815Y779065D01*
G01X500295Y401715D02*
X500462Y401882D01*
X504094D01*
G01X500526Y394177D02*
X504316D01*
G01Y397677D02*
Y401660D01*
X504094Y401882D01*
G01D02*
X505896D01*
X507439Y403425D01*
X510634D01*
G01X503981Y420469D02*
Y423852D01*
X503923Y423910D01*
G01X519466Y424009D02*
X523410D01*
X523462Y423957D01*
X64964Y416068D03*
X68901D03*
X72838D03*
X76775D03*
X64964Y412131D03*
X68901D03*
X72838D03*
X76775D03*
X64964Y408194D03*
X68901D03*
X72838D03*
X76775D03*
X64964Y404257D03*
X68901D03*
X72838D03*
X76775D03*
X64964Y400320D03*
X68901D03*
X72838D03*
X76775D03*
Y396383D03*
Y392446D03*
Y388509D03*
X64964Y482998D03*
X68901D03*
X72838D03*
X76775D03*
X64964Y479061D03*
X68901D03*
X72838D03*
X76775D03*
X64964Y475124D03*
X68901D03*
X72838D03*
X76775D03*
X64964Y471187D03*
X68901D03*
X72838D03*
X76775D03*
X64964Y467250D03*
X68901D03*
X72838D03*
X76775D03*
X64964Y463313D03*
X68901D03*
X72838D03*
X76775D03*
X64964Y459376D03*
X68901D03*
X72838D03*
X76775D03*
X64964Y455439D03*
X68901D03*
X72838D03*
X76775D03*
X64964Y451502D03*
X68901D03*
X72838D03*
X76775D03*
X64964Y447565D03*
X68901D03*
X72838D03*
X76775D03*
X64964Y443628D03*
X68901D03*
X72838D03*
X76775D03*
X64964Y439690D03*
X68901D03*
X72838D03*
X76775D03*
X64964Y435753D03*
X68901D03*
X72838D03*
X76775D03*
X64964Y431816D03*
X68901D03*
X72838D03*
X76775D03*
X64964Y427879D03*
X68901D03*
X72838D03*
X76775D03*
X64964Y423942D03*
X68901D03*
X72838D03*
X76775D03*
X64964Y420005D03*
X68901D03*
X72838D03*
X76775D03*
Y494809D03*
Y490872D03*
Y486935D03*
X80712Y416068D03*
X84649D03*
X88586D03*
X92523D03*
X96460D03*
X100397D03*
X104334D03*
X108271D03*
X112208D03*
X116145D03*
X120083D03*
X124020D03*
X127957D03*
X131894D03*
X135831D03*
X139768D03*
X143705D03*
X147642D03*
X80712Y412131D03*
X84649D03*
X88586D03*
X92523D03*
X96460D03*
X100397D03*
X104334D03*
X108271D03*
X112208D03*
X116145D03*
X120083D03*
X124020D03*
X127957D03*
X131894D03*
X135831D03*
X139768D03*
X143705D03*
X147642D03*
X80712Y408194D03*
X84649D03*
X88586D03*
X92523D03*
X96460D03*
X100397D03*
X104334D03*
X108271D03*
X112208D03*
X116145D03*
X120083D03*
X124020D03*
X127957D03*
X131894D03*
X135831D03*
X139768D03*
X143705D03*
X147642D03*
X80712Y404257D03*
X84649D03*
X88586D03*
X92523D03*
X96460D03*
X100397D03*
X104334D03*
X108271D03*
X112208D03*
X116145D03*
X120083D03*
X124020D03*
X127957D03*
X131894D03*
X135831D03*
X139768D03*
X143705D03*
X147642D03*
X80712Y400320D03*
X84649D03*
X88586D03*
X92523D03*
X96460D03*
X100397D03*
X104334D03*
X108271D03*
X112208D03*
X116145D03*
X120083D03*
X124020D03*
X127957D03*
X131894D03*
X135831D03*
X139768D03*
X143705D03*
X147642D03*
X80712Y396383D03*
X84649D03*
X88586D03*
X92523D03*
X96460D03*
X100397D03*
X104334D03*
X108271D03*
X112208D03*
X116145D03*
X120083D03*
X124020D03*
X127957D03*
X131894D03*
X135831D03*
X139768D03*
X143705D03*
X147642D03*
X80712Y392446D03*
X84649D03*
X88586D03*
X92523D03*
X96460D03*
X100397D03*
X104334D03*
X108271D03*
X112208D03*
X116145D03*
X120083D03*
X124020D03*
X127957D03*
X131894D03*
X135831D03*
X139768D03*
X143705D03*
X147642D03*
X80712Y388509D03*
X84649D03*
X88586D03*
X92523D03*
X96460D03*
X100397D03*
X104334D03*
X108271D03*
X112208D03*
X116145D03*
X120083D03*
X124020D03*
X127957D03*
X131894D03*
X135831D03*
X139768D03*
X143705D03*
X147642D03*
X80712Y482998D03*
X84649D03*
X88586D03*
X92523D03*
X96460D03*
X100397D03*
X104334D03*
X108271D03*
X112208D03*
X116145D03*
X120083D03*
X124020D03*
X127957D03*
X131894D03*
X135831D03*
X139768D03*
X143705D03*
X147642D03*
X80712Y479061D03*
X84649D03*
X88586D03*
X92523D03*
X96460D03*
X100397D03*
X104334D03*
X108271D03*
X112208D03*
X116145D03*
X120083D03*
X124020D03*
X127957D03*
X131894D03*
X135831D03*
X139768D03*
X143705D03*
X147642D03*
X80712Y475124D03*
X84649D03*
X88586D03*
X92523D03*
X96460D03*
X100397D03*
X104334D03*
X108271D03*
X112208D03*
X116145D03*
X120083D03*
X124020D03*
X127957D03*
X131894D03*
X135831D03*
X139768D03*
X143705D03*
X147642D03*
X80712Y471187D03*
X84649D03*
X88586D03*
X92523D03*
X96460D03*
X100397D03*
X104334D03*
X108271D03*
X112208D03*
X116145D03*
X120083D03*
X124020D03*
X127957D03*
X131894D03*
X135831D03*
X139768D03*
X143705D03*
X147642D03*
X80712Y467250D03*
X84649D03*
X88586D03*
X92523D03*
X96460D03*
X100397D03*
X104334D03*
X108271D03*
X112208D03*
X116145D03*
X120083D03*
X124020D03*
X127957D03*
X131894D03*
X135831D03*
X139768D03*
X143705D03*
X147642D03*
X80712Y463313D03*
X84649D03*
X88586D03*
X92523D03*
X96460D03*
X100397D03*
X104334D03*
X108271D03*
X112208D03*
X116145D03*
X120083D03*
X124020D03*
X127957D03*
X131894D03*
X135831D03*
X139768D03*
X143705D03*
X147642D03*
X80712Y459376D03*
X84649D03*
X88586D03*
X92523D03*
X96460D03*
X100397D03*
X104334D03*
X108271D03*
X112208D03*
X116145D03*
X120083D03*
X124020D03*
X127957D03*
X131894D03*
X135831D03*
X139768D03*
X143705D03*
X147642D03*
X80712Y455439D03*
X84649D03*
X88586D03*
X92523D03*
X96460D03*
X100397D03*
X104334D03*
X108271D03*
X112208D03*
X116145D03*
X120083D03*
X124020D03*
X127957D03*
X131894D03*
X135831D03*
X139768D03*
X143705D03*
X147642D03*
X80712Y451502D03*
X84649D03*
X88586D03*
X92523D03*
X96460D03*
X100397D03*
X104334D03*
X108271D03*
X112208D03*
X116145D03*
X120083D03*
X124020D03*
X127957D03*
X131894D03*
X135831D03*
X139768D03*
X143705D03*
X147642D03*
X80712Y447565D03*
X84649D03*
X88586D03*
X92523D03*
X96460D03*
X100397D03*
X104334D03*
X108271D03*
X112208D03*
X116145D03*
X120083D03*
X124020D03*
X127957D03*
X131894D03*
X135831D03*
X139768D03*
X143705D03*
X147642D03*
X80712Y443628D03*
X84649D03*
X88586D03*
X92523D03*
X96460D03*
X100397D03*
X104334D03*
X108271D03*
X112208D03*
X116145D03*
X120083D03*
X124020D03*
X127957D03*
X131894D03*
X135831D03*
X139768D03*
X143705D03*
X147642D03*
X80712Y439690D03*
X84649D03*
X88586D03*
X92523D03*
X96460D03*
X100397D03*
X104334D03*
X108271D03*
X112208D03*
X116145D03*
X120083D03*
X124020D03*
X127957D03*
X131894D03*
X135831D03*
X139768D03*
X143705D03*
X147642D03*
X80712Y435753D03*
X84649D03*
X88586D03*
X92523D03*
X96460D03*
X100397D03*
X104334D03*
X108271D03*
X112208D03*
X116145D03*
X120083D03*
X124020D03*
X127957D03*
X131894D03*
X135831D03*
X139768D03*
X143705D03*
X147642D03*
X80712Y431816D03*
X84649D03*
X88586D03*
X92523D03*
X96460D03*
X100397D03*
X104334D03*
X108271D03*
X112208D03*
X116145D03*
X120083D03*
X124020D03*
X127957D03*
X131894D03*
X135831D03*
X139768D03*
X143705D03*
X147642D03*
X80712Y427879D03*
X84649D03*
X88586D03*
X92523D03*
X96460D03*
X100397D03*
X104334D03*
X108271D03*
X112208D03*
X116145D03*
X120083D03*
X124020D03*
X127957D03*
X131894D03*
X135831D03*
X139768D03*
X143705D03*
X147642D03*
X80712Y423942D03*
X84649D03*
X88586D03*
X92523D03*
X96460D03*
X100397D03*
X104334D03*
X108271D03*
X112208D03*
X116145D03*
X120083D03*
X124020D03*
X127957D03*
X131894D03*
X135831D03*
X139768D03*
X143705D03*
X147642D03*
X80712Y420005D03*
X84649D03*
X88586D03*
X92523D03*
X96460D03*
X100397D03*
X104334D03*
X108271D03*
X112208D03*
X116145D03*
X120083D03*
X124020D03*
X127957D03*
X131894D03*
X135831D03*
X139768D03*
X143705D03*
X147642D03*
X80712Y494809D03*
X84649D03*
X88586D03*
X92523D03*
X96460D03*
X100397D03*
X104334D03*
X108271D03*
X112208D03*
X116145D03*
X120083D03*
X124020D03*
X127957D03*
X131894D03*
X135831D03*
X139768D03*
X143705D03*
X147642D03*
X80712Y490872D03*
X84649D03*
X88586D03*
X92523D03*
X96460D03*
X100397D03*
X104334D03*
X108271D03*
X112208D03*
X116145D03*
X120083D03*
X124020D03*
X127957D03*
X131894D03*
X135831D03*
X139768D03*
X143705D03*
X147642D03*
X80712Y486935D03*
X84649D03*
X88586D03*
X92523D03*
X96460D03*
X100397D03*
X104334D03*
X108271D03*
X112208D03*
X116145D03*
X120083D03*
X124020D03*
X127957D03*
X131894D03*
X135831D03*
X139768D03*
X143705D03*
X147642D03*
X163390Y416068D03*
X167327D03*
X171264D03*
X163390Y412131D03*
X167327D03*
X171264D03*
X163390Y408194D03*
X167327D03*
X171264D03*
X163390Y404257D03*
X167327D03*
X171264D03*
X163390Y400320D03*
X167327D03*
X171264D03*
X151579Y416068D03*
X155516D03*
X159453D03*
X151579Y412131D03*
X155516D03*
X159453D03*
X151579Y408194D03*
X155516D03*
X159453D03*
X151579Y404257D03*
X155516D03*
X159453D03*
X151579Y400320D03*
X155516D03*
X159453D03*
X151579Y396383D03*
X155516D03*
X159453D03*
X151579Y392446D03*
X155516D03*
X159453D03*
X151579Y388509D03*
X155516D03*
X159453D03*
X163390Y482998D03*
X167327D03*
X171264D03*
X163390Y479061D03*
X167327D03*
X171264D03*
X163390Y475124D03*
X167327D03*
X171264D03*
X163390Y471187D03*
X167327D03*
X171264D03*
X163390Y467250D03*
X167327D03*
X171264D03*
X163390Y463313D03*
X167327D03*
X171264D03*
X163390Y459376D03*
X167327D03*
X171264D03*
X163390Y455439D03*
X167327D03*
X171264D03*
X163390Y451502D03*
X167327D03*
X171264D03*
X163390Y447565D03*
X167327D03*
X171264D03*
X163390Y443628D03*
X167327D03*
X171264D03*
X163390Y439690D03*
X167327D03*
X171264D03*
X163390Y435753D03*
X167327D03*
X171264D03*
X163390Y431816D03*
X167327D03*
X171264D03*
X163390Y427879D03*
X167327D03*
X171264D03*
X163390Y423942D03*
X167327D03*
X171264D03*
X163390Y420005D03*
X167327D03*
X171264D03*
X151579Y482998D03*
X155516D03*
X159453D03*
X151579Y479061D03*
X155516D03*
X159453D03*
X151579Y475124D03*
X155516D03*
X159453D03*
X151579Y471187D03*
X155516D03*
X159453D03*
X151579Y467250D03*
X155516D03*
X159453D03*
X151579Y463313D03*
X155516D03*
X159453D03*
X151579Y459376D03*
X155516D03*
X159453D03*
X151579Y455439D03*
X155516D03*
X159453D03*
X151579Y451502D03*
X155516D03*
X159453D03*
X151579Y447565D03*
X155516D03*
X159453D03*
X151579Y443628D03*
X155516D03*
X159453D03*
X151579Y439690D03*
X155516D03*
X159453D03*
X151579Y435753D03*
X155516D03*
X159453D03*
X151579Y431816D03*
X155516D03*
X159453D03*
X151579Y427879D03*
X155516D03*
X159453D03*
X151579Y423942D03*
X155516D03*
X159453D03*
X151579Y420005D03*
X155516D03*
X159453D03*
X151579Y494809D03*
X155516D03*
X159453D03*
X151579Y490872D03*
X155516D03*
X159453D03*
X151579Y486935D03*
X155516D03*
X159453D03*
G54D19*
X43100Y103500D03*
X46863Y378983D03*
X65763Y370883D03*
X59384Y637701D03*
X84296Y192448D03*
X149031Y168900D03*
X115096Y186970D03*
X79922Y632686D03*
X80191Y647887D03*
X80653Y747704D03*
X80464Y764806D03*
X217113Y130860D03*
X172685Y172033D03*
X168353Y140290D03*
X189415Y413533D03*
X185266Y481943D03*
X225231Y61620D03*
X225002Y130816D03*
X231350Y214208D03*
X226428Y395041D03*
X222254Y394949D03*
X236637Y383693D03*
X241728Y364256D03*
X237455Y375355D03*
X246800Y436600D03*
X231108Y464137D03*
X226992Y464083D03*
X537200Y394400D03*
X657609Y470923D03*
X661709Y466823D03*
X674109Y454523D03*
X678509Y450323D03*
X654800Y529500D03*
X736209Y475223D03*
X740309Y479423D03*
X723809Y462723D03*
X719709Y458623D03*
G54D28*
X77200Y199800D03*
X24390Y497166D03*
X95441Y203600D03*
X215461Y461171D03*
X215434Y464704D03*
X229600Y454700D03*
X294900Y466600D03*
X475128Y493916D03*
X456920Y493874D03*
G54D64*
X193000Y130850D03*
Y146350D03*
X274405Y63139D03*
Y47639D03*
G54D37*
X33253Y486907D03*
X25653D03*
X33250Y479024D03*
X25650D03*
X245837Y83579D03*
X253437D03*
X302287Y456235D03*
X294687D03*
X653800Y520900D03*
X646200D03*
X653819Y513168D03*
X646219D03*
G54D46*
X52900Y645300D03*
Y634300D03*
Y748300D03*
Y759300D03*
X205600Y135800D03*
Y146800D03*
X294751Y448610D03*
Y437610D03*
X303549Y448556D03*
Y437556D03*
G54D73*
X200788Y473418D03*
X216324D03*
X200788Y493918D03*
X216324D03*
G54D55*
X154113Y195199D03*
G54D91*
X781514Y330730D03*
Y334665D03*
Y338605D03*
Y342540D03*
Y381910D03*
Y385850D03*
Y389785D03*
Y393720D03*
Y397660D03*
Y401595D03*
Y405535D03*
Y409470D03*
Y413405D03*
Y346480D03*
Y350415D03*
Y354350D03*
Y358290D03*
Y362225D03*
Y366165D03*
Y370100D03*
Y417345D03*
Y421280D03*
Y425220D03*
Y429155D03*
Y433090D03*
Y437030D03*
Y440965D03*
Y444905D03*
Y448840D03*
Y452775D03*
Y456715D03*
Y460650D03*
Y464590D03*
Y468525D03*
Y472460D03*
Y476400D03*
Y480335D03*
Y484275D03*
Y488210D03*
Y492145D03*
Y496085D03*
Y500020D03*
Y503960D03*
Y507895D03*
Y511830D03*
Y515770D03*
Y519705D03*
Y523645D03*
Y527580D03*
Y531515D03*
Y535455D03*
Y539390D03*
Y543330D03*
Y547265D03*
Y551200D03*
Y555140D03*
Y559075D03*
Y563015D03*
Y566950D03*
Y570885D03*
Y574825D03*
Y578760D03*
Y582700D03*
Y586635D03*
Y590575D03*
Y594510D03*
Y598445D03*
Y602385D03*
Y606320D03*
Y610260D03*
Y614195D03*
Y618130D03*
Y622070D03*
Y626005D03*
Y629945D03*
Y633880D03*
Y637815D03*
Y641755D03*
Y645690D03*
Y649630D03*
Y657500D03*
Y740179D03*
Y744114D03*
Y748054D03*
Y751989D03*
Y755929D03*
Y759864D03*
Y763799D03*
Y767739D03*
Y779549D03*
Y771674D03*
Y775614D03*
Y791359D03*
Y795299D03*
Y799234D03*
Y803169D03*
Y807109D03*
Y814984D03*
G54D82*
X286982Y828335D03*
X276982D03*
X286982Y818335D03*
X276982D03*
X356982Y828335D03*
X346982D03*
X336982D03*
X326982D03*
X316982D03*
X306982D03*
X296982D03*
X356982Y818335D03*
X346982D03*
X336982D03*
X326982D03*
X316982D03*
X306982D03*
X296982D03*
X366982Y828335D03*
Y818335D03*
G54D38*
X27990Y497166D03*
X80800Y199800D03*
X99041Y203600D03*
X219061Y461171D03*
X219034Y464704D03*
X233200Y454700D03*
X298500Y466600D03*
X478728Y493916D03*
X460520Y493874D03*
G54D56*
X129310Y186223D03*
Y204175D03*
G54D74*
X216324Y483668D03*
X200788D03*
G54D29*
X43760Y172352D03*
X69800Y180800D03*
X103041Y203500D03*
X115041Y202800D03*
X144600Y233900D03*
X214190Y98033D03*
X199561Y113456D03*
X189163Y240983D03*
X189121Y244556D03*
X189163Y248183D03*
Y237383D03*
X185309Y421839D03*
X189466Y493343D03*
X249782Y399333D03*
X249041Y383206D03*
X241555Y375055D03*
X241530Y371576D03*
X245865Y363969D03*
X245828Y360456D03*
X237500Y454700D03*
X223399Y778667D03*
X487203Y501502D03*
X487218Y494161D03*
X487223Y497927D03*
X515916Y424009D03*
X517452Y552477D03*
X517613Y548807D03*
X693339Y759399D03*
X693392Y762972D03*
X694427Y817304D03*
X694375Y820842D03*
G54D65*
X166649Y132747D03*
G54D92*
X779564Y653565D03*
Y811044D03*
G54D83*
X501750Y380000D03*
X520250D03*
G54D47*
X59800Y764900D03*
X93130Y145135D03*
X212000Y171900D03*
X201547Y407074D03*
X207141Y386759D03*
X185614Y458881D03*
X215006Y438401D03*
X190714Y458681D03*
X247262Y519409D03*
G54D93*
G01X250867Y69296D02*
X256923D01*
X256928Y69301D01*
G54D39*
X77453Y525824D03*
X69970Y521539D03*
X66497Y521555D03*
X59007Y525728D03*
X55470Y525648D03*
X47790Y521300D03*
X44031Y521396D03*
X136663Y521903D03*
X133163Y522003D03*
X147678Y526068D03*
X144206Y526034D03*
X125501Y526046D03*
X122044Y526062D03*
X114546Y521952D03*
X110786Y521951D03*
X103330Y525965D03*
X99797Y525846D03*
X92158Y521634D03*
X88606Y521633D03*
X81117Y525760D03*
X204811Y77927D03*
X153061Y168712D03*
X219655Y214498D03*
X200498Y388564D03*
X205667Y406683D03*
X214163Y526003D03*
X210563Y526103D03*
X202963Y521903D03*
X199363D03*
X191863Y526203D03*
X188363D03*
X180845Y521911D03*
X177324Y521927D03*
X169812Y526147D03*
X166180Y526146D03*
X158691Y521893D03*
X155181Y521942D03*
X258530Y81926D03*
X243200Y520700D03*
X277254Y845565D03*
X337612Y430423D03*
X341344D03*
X360415D03*
X356714D03*
X352814D03*
X348914D03*
X345014D03*
X387100D03*
X383102D03*
X371187D03*
X367432D03*
X363968D03*
X379184D03*
X375464D03*
G54D48*
X59800Y770500D03*
X93130Y150735D03*
X212000Y177500D03*
X201547Y412674D03*
X207141Y392359D03*
X185614Y464481D03*
X215006Y444001D03*
X190714Y464281D03*
X247262Y525009D03*
G54D75*
X194548Y827952D03*
Y837401D03*
Y846849D03*
G54D66*
X164396Y151107D03*
Y165087D03*
X170302D03*
Y151107D03*
G54D84*
X497166Y535119D03*
Y537679D03*
Y540239D03*
Y542799D03*
X519366D03*
Y540239D03*
Y537679D03*
Y535119D03*
X695412Y836919D03*
Y834419D03*
Y831919D03*
Y829419D03*
Y826919D03*
X696098Y796516D03*
Y794016D03*
Y791516D03*
Y789016D03*
Y786516D03*
Y784016D03*
Y781516D03*
Y779016D03*
Y776516D03*
Y774016D03*
Y771516D03*
Y769016D03*
X695412Y854419D03*
Y851919D03*
Y849419D03*
Y846919D03*
Y844419D03*
Y841919D03*
Y839419D03*
X716012Y826919D03*
Y829419D03*
Y831919D03*
Y834419D03*
Y836919D03*
X716698Y769016D03*
Y771516D03*
Y774016D03*
Y776516D03*
Y779016D03*
Y781516D03*
Y784016D03*
Y786516D03*
Y789016D03*
Y791516D03*
Y794016D03*
Y796516D03*
X716012Y839419D03*
Y841919D03*
Y844419D03*
Y846919D03*
Y849419D03*
Y851919D03*
Y854419D03*
G54D57*
X104382Y212614D03*
X99525Y212610D03*
X212700Y129700D03*
X168084Y172055D03*
X212492Y403033D03*
X217363Y401778D03*
X185934Y470229D03*
X203439Y459352D03*
X194624Y421463D03*
X190765Y470328D03*
X264353Y484934D03*
X222577Y522519D03*
X341430Y463151D03*
X371408Y393555D03*
X366586D03*
X361719D03*
G54D94*
G01X58059Y88738D02*
X61245D01*
X61807Y89300D01*
X63400D01*
G01X82400Y89500D02*
X81638Y88738D01*
X74359D01*
G01X66540Y193550D02*
X60200D01*
G01X69569Y594959D02*
X70820D01*
X71530Y595669D01*
X75117D01*
X75118Y595670D01*
G01X115096Y190420D02*
X114265Y191251D01*
G01D02*
X107899D01*
G01X91599Y189286D02*
X96900D01*
G01X206470Y93789D02*
Y93261D01*
X209347Y90384D01*
Y89053D01*
X209800Y88600D01*
G01X216447Y86070D02*
X212330D01*
X209800Y88600D01*
G01X216447Y91976D02*
Y96740D01*
X217740Y98033D01*
G01X174339Y158097D02*
X177703D01*
G01X177634Y160066D02*
X174339D01*
G01X182263Y162034D02*
X183034Y162805D01*
G01X174339Y162034D02*
X182263D01*
G01X154800Y145800D02*
X154641Y145959D01*
Y150898D01*
G01D02*
X158998D01*
X160359Y152259D01*
Y154160D01*
G01Y156128D02*
X156371D01*
X154641Y154398D01*
G01X156100Y158000D02*
X156197Y158097D01*
X160359D01*
G01X174339Y154160D02*
Y151172D01*
G01X168010Y267909D02*
X167851Y268068D01*
X157763D01*
G01X219717Y211198D02*
Y214486D01*
X219655Y214548D01*
G01X151519Y250193D02*
Y250146D01*
X153297Y248368D01*
X157763D01*
G01X152580Y285530D02*
X152848Y285798D01*
X157763D01*
G01X159926Y813000D02*
Y813926D01*
X160740Y814740D01*
X160743D01*
X162226Y816216D01*
X162234Y816233D01*
X162929Y816929D01*
X165238D01*
G01X181772Y818429D02*
X181697Y818504D01*
X175118D01*
G01X181642Y827853D02*
X181541Y827954D01*
X175118D01*
G01X181642Y837321D02*
X181564Y837399D01*
X175118D01*
G01X158725Y835536D02*
X159018Y835829D01*
X165238D01*
G01X157422Y825918D02*
X157883Y826379D01*
X165238D01*
G01X181124Y847013D02*
X180960Y846849D01*
X175118D01*
G01X181081Y856307D02*
X181073Y856299D01*
X175118D01*
G01X235733Y84102D02*
X238229D01*
X241101Y81230D01*
G01D02*
X244596Y77735D01*
G01X245837Y83579D02*
X242576D01*
X241132Y85023D01*
G01D02*
X240085Y86070D01*
X235733D01*
G01Y90007D02*
X238689D01*
X241982Y93300D01*
X242800D01*
G01X235733Y91976D02*
Y98536D01*
X238615Y101418D01*
Y101568D01*
X238771Y101724D01*
G01X244740Y98033D02*
X244240Y98533D01*
X242415D01*
X239224Y101724D01*
X238771D01*
G01X228249Y188760D02*
X231049D01*
G01X220569Y204940D02*
Y210346D01*
X219717Y211198D01*
G01X235250Y448600D02*
Y452400D01*
X237550Y454700D01*
G01X220250Y448600D02*
Y453150D01*
X221035Y453935D01*
G01D02*
X222750Y452220D01*
Y448600D01*
G01X223449Y778667D02*
X220569Y775787D01*
Y771870D01*
G01X483008Y500529D02*
Y502292D01*
X481168Y504132D01*
X476320D01*
G01X497166Y535119D02*
X502109D01*
X502318Y535328D01*
G01X460020Y504132D02*
X465111D01*
G01D02*
X465900Y503343D01*
Y501200D01*
G01X451123Y503933D02*
X453667D01*
X455438Y502162D01*
X460020D01*
G01X460470Y493874D02*
X460020Y494324D01*
Y500197D01*
G01X476320D02*
Y498341D01*
X478129Y496532D01*
Y494465D01*
X478678Y493916D01*
G01X487268Y494161D02*
X485342Y494262D01*
X484738D01*
X480420Y498580D01*
Y501573D01*
X479831Y502162D01*
X476320D01*
G01X517663Y548807D02*
Y546900D01*
X519366Y545197D01*
Y542799D01*
G01X682986Y532186D02*
Y531886D01*
X682000Y530900D01*
Y528887D01*
G01X672257Y533512D02*
Y538800D01*
X672168Y538889D01*
G01X658314Y526697D02*
X658683Y526328D01*
X662514D01*
G01X654800Y529450D02*
X655561D01*
X658314Y526697D01*
G01X669698Y538232D02*
Y533512D01*
G01X696098Y769016D02*
Y767698D01*
X693256Y764856D01*
Y763158D01*
X693442Y762972D01*
G01X694477Y817304D02*
X694425Y817356D01*
Y820842D01*
G01X691075Y820814D02*
X691172D01*
X691200Y820842D01*
X694425D01*
G01D02*
X695124Y821541D01*
Y822001D01*
X695412Y822289D01*
Y826919D01*
G01X716698Y796516D02*
X711116D01*
G01X716012Y854419D02*
X721112D01*
G54D85*
X510634Y403425D03*
Y408425D03*
Y413425D03*
X530634D03*
Y408425D03*
Y403425D03*
X510634Y418425D03*
X530634D03*
G54D67*
X160359Y154160D03*
Y156128D03*
Y158097D03*
Y160066D03*
Y162034D03*
X174339D03*
Y160066D03*
Y158097D03*
Y156128D03*
Y154160D03*
G54D58*
X104382Y218214D03*
X99525Y218210D03*
X212700Y135300D03*
X168084Y177655D03*
X212492Y408633D03*
X217363Y407378D03*
X185934Y475829D03*
X203439Y464952D03*
X194624Y427063D03*
X190765Y475928D03*
X222577Y528119D03*
X264353Y490534D03*
X341430Y468751D03*
X371408Y399155D03*
X366586D03*
X361719D03*
G54D76*
X226090Y82133D03*
G54D49*
X151400Y54700D03*
X116689Y54714D03*
X103528D03*
X151400Y66300D03*
X116689Y66314D03*
X103528D03*
X164500Y54700D03*
Y66300D03*
G54D95*
G01X251700Y135484D02*
X297915D01*
G01D02*
X365131D01*
G01X633923Y520400D02*
Y530113D01*
G54D68*
X167349Y158097D03*
G54D86*
X513500Y396160D03*
Y393600D03*
Y391040D03*
X520900D03*
Y393600D03*
Y396160D03*
G54D77*
X246455Y107157D03*
G54D59*
X140847Y223231D03*
X162963D03*
G54D96*
G01X63413Y254683D02*
X60403D01*
X60009Y255077D01*
G01X63413Y262883D02*
Y258783D01*
G01X60102Y263180D02*
X60399Y262883D01*
X63413D01*
G01Y267083D02*
X63161D01*
X60102Y264024D01*
Y263180D01*
G01X63613Y250483D02*
Y246283D01*
G01D02*
X59865D01*
X59258Y246890D01*
G01X63513Y242083D02*
Y237783D01*
X63613Y237683D01*
G01D02*
X60351D01*
X60069Y237965D01*
G01X69220Y614992D02*
X69646Y614566D01*
X75117D01*
X75118Y614567D01*
G01X69518Y604727D02*
X69576D01*
X69966Y605117D01*
X75117D01*
X75118Y605118D01*
G01X69323Y579887D02*
X69357Y579921D01*
X75117D01*
X75118Y579922D01*
G01X68421Y570392D02*
X68501Y570472D01*
X75117D01*
X75118Y570473D01*
G01X69520Y560987D02*
X69556Y561023D01*
X75117D01*
X75118Y561024D01*
G01X69911Y676938D02*
X72106Y679133D01*
X75119D01*
X75118Y679134D01*
G01X69316Y697605D02*
X69742Y698031D01*
X75119D01*
X75118Y698032D01*
G01X68928Y687846D02*
X69184Y688102D01*
X70652D01*
X71132Y688582D01*
X75119D01*
X75118Y688583D01*
G01X69217Y732676D02*
X75117D01*
X75118Y732677D01*
G01X68620Y722610D02*
X69237Y723227D01*
X75119D01*
X75118Y723228D01*
G01X69558Y711913D02*
X70400D01*
X70699Y712212D01*
X70724D01*
X72291Y713779D01*
X75119D01*
X75118Y713780D01*
G01X90923Y616187D02*
X90877Y616141D01*
X85001D01*
X85000Y616142D01*
G01X91023Y606587D02*
X90918Y606692D01*
X85001D01*
X85000Y606693D01*
G01X91343Y598284D02*
X91334D01*
Y598255D01*
X90322Y597243D01*
X85001D01*
X85000Y597244D01*
G01X90823Y581387D02*
X90715Y581495D01*
X85001D01*
X85000Y581496D01*
G01X91156Y572112D02*
X91091Y572047D01*
X85001D01*
X85000Y572048D01*
G01X91852Y563129D02*
X91321Y562598D01*
X85001D01*
X85000Y562599D01*
G01X90174Y678675D02*
X88141Y680708D01*
X85001D01*
X85000Y680709D01*
G01X90681Y690157D02*
X85001D01*
X85000Y690158D01*
G01X91094Y715818D02*
X90629Y715353D01*
X85001D01*
X85000Y715354D01*
G01X91027Y724985D02*
X90844Y724802D01*
X85001D01*
X85000Y724803D01*
G01X90814Y734451D02*
X90680D01*
X90480Y734251D01*
X85001D01*
X85000Y734252D01*
G01X93840Y699686D02*
X93510Y699356D01*
X89355D01*
X89106Y699605D01*
X85001D01*
X85000Y699606D01*
G01X154730Y847010D02*
X155028D01*
X156764Y845274D01*
X165238D01*
G01X160735Y857183D02*
X163194Y854724D01*
X165238D01*
G01X228249Y755690D02*
Y761450D01*
G01X513500Y396160D02*
Y399060D01*
G01X520900Y391040D02*
Y388100D01*
G54D69*
X166649Y135247D03*
G54D78*
X246455Y109657D03*
G54D87*
X672257Y523769D03*
G54D97*
G01X173425Y390228D02*
X173393Y390196D01*
X170331D01*
X168081Y392446D01*
X167327D01*
G54D79*
X220569Y204940D03*
X223129D03*
X225689D03*
X228249D03*
Y188760D03*
X225689D03*
X223129D03*
X220569D03*
X237750Y428000D03*
X235250D03*
X232750D03*
X230250D03*
X227750D03*
X225250D03*
X222750D03*
X220250D03*
Y448600D03*
X222750D03*
X225250D03*
X227750D03*
X230250D03*
X232750D03*
X235250D03*
X237750D03*
X228249Y755690D03*
X225689D03*
X223129D03*
X220569D03*
Y771870D03*
X223129D03*
X225689D03*
X228249D03*
G54D88*
X662514Y518651D03*
Y521210D03*
Y523769D03*
Y526328D03*
Y528887D03*
X682000D03*
Y526328D03*
Y523769D03*
Y521210D03*
Y518651D03*
G54D98*
G01X69850Y180800D02*
Y182650D01*
X71660Y184460D01*
Y187050D01*
G54D89*
X667139Y533512D03*
X669698D03*
X672257D03*
X674816D03*
X677375D03*
Y514026D03*
X674816D03*
X672257D03*
X669698D03*
X667139D03*
G54D99*
G01X56620Y19685D02*
X76772D01*
G01D02*
X96924D01*
G01X29528D02*
Y39837D01*
G01X9376Y19685D02*
X29528D01*
G01D02*
X49680D01*
G01X53547Y298334D02*
Y302486D01*
G01D02*
Y306638D01*
G01X49395Y302486D02*
X53547D01*
G01Y318334D02*
Y322486D01*
G01D02*
Y326638D01*
G01X49395Y322486D02*
X53547D01*
G01D02*
X57699D01*
G01X135360Y905512D02*
X155512D01*
G01X88116D02*
X108268D01*
G01D02*
X128420D01*
G01X182681Y556680D02*
Y560832D01*
G01D02*
Y564984D01*
G01X178529Y560832D02*
X182681D01*
G01D02*
X186833D01*
G01X182681Y576680D02*
Y580832D01*
G01D02*
Y584984D01*
G01X178529Y580832D02*
X182681D01*
G01D02*
X186833D01*
G01X155512Y905512D02*
X175664D01*
G01X286982Y823883D02*
Y828335D01*
G01D02*
Y832787D01*
G01X282530Y828335D02*
X286982D01*
G01D02*
X291434D01*
G01X296982Y823883D02*
Y828335D01*
G01D02*
Y832787D01*
G01X292530Y828335D02*
X296982D01*
G01D02*
X301434D01*
G01X306982Y823883D02*
Y828335D01*
G01D02*
Y832787D01*
G01X302530Y828335D02*
X306982D01*
G01D02*
X311434D01*
G01X316982Y823883D02*
Y828335D01*
G01D02*
Y832787D01*
G01X312530Y828335D02*
X316982D01*
G01D02*
X321434D01*
G01X326982Y823883D02*
Y828335D01*
G01D02*
Y832787D01*
G01X322530Y828335D02*
X326982D01*
G01D02*
X331434D01*
G01X336982Y823883D02*
Y828335D01*
G01D02*
Y832787D01*
G01X332530Y828335D02*
X336982D01*
G01D02*
X341434D01*
G01X346982Y823883D02*
Y828335D01*
G01D02*
Y832787D01*
G01X342530Y828335D02*
X346982D01*
G01D02*
X351434D01*
G01X356982Y823883D02*
Y828335D01*
G01D02*
Y832787D01*
G01X352530Y828335D02*
X356982D01*
G01D02*
X361434D01*
G01X366982Y823883D02*
Y828335D01*
G01D02*
Y832787D01*
G01X362530Y828335D02*
X366982D01*
G01D02*
X371434D01*
M02*
